FILE_TYPE = MACRO_DRAWING;
SET COLOR_WIRE YELLOW;
SET COLOR_PROP MONO;
SET COLOR_DOT WHITE;
SET COLOR_ARC YELLOW;
SET COLOR_BODY GREEN;
SET COLOR_NOTE MONO;
SET PROP_DISPLAY VALUE;
SET PAGE_NUMBER P129;
FORCEADD OFFPAGE..2
(2150 5025);
FORCEPROP 2 LAST $XR0 117 
J 0
(2339 5025);
DISPLAY 0.638298 (2339 5025);
PAINT MONO (2339 5025);
FORCEPROP 2 LAST BOM_COST SB
J 0
(2475 5075);
DISPLAY 0.744681 (2475 5075);
PAINT MONO (2475 5075);
DISPLAY INVISIBLE (2475 5075);
FORCEPROP 2 LAST CDS_LIB mstr_standard
J 0
(2150 5025);
PAINT ORANGE (2150 5025);
DISPLAY INVISIBLE (2150 5025);
FORCEPROP 1 LAST OFFPAGE TRUE
J 0
(2475 4900);
DISPLAY 0.872340 (2475 4900);
PAINT GREEN (2475 4900);
DISPLAY INVISIBLE (2475 4900);
FORCEPROP 1 LAST COMMENT_BODY TRUE
J 0
(2105 4930);
DISPLAY 0.872340 (2105 4930);
PAINT PEACH (2105 4930);
DISPLAY INVISIBLE (2105 4930);
FORCEPROP 2 LAST PATH I1
J 0
(2500 5100);
DISPLAY 1.021277 (2500 5100);
PAINT ORANGE (2500 5100);
DISPLAY INVISIBLE (2500 5100);
FORCEADD OFFPAGE..2
(2150 4075);
FORCEPROP 2 LAST $XR0 29 
J 0
(2339 4075);
DISPLAY 0.638298 (2339 4075);
PAINT MONO (2339 4075);
FORCEPROP 2 LAST BOM_COST SB
J 0
(2450 4125);
DISPLAY 0.744681 (2450 4125);
PAINT MONO (2450 4125);
DISPLAY INVISIBLE (2450 4125);
FORCEPROP 2 LAST CDS_LIB mstr_standard
J 0
(2150 4075);
PAINT ORANGE (2150 4075);
DISPLAY INVISIBLE (2150 4075);
FORCEPROP 1 LAST OFFPAGE TRUE
J 0
(2475 3950);
DISPLAY 0.872340 (2475 3950);
PAINT GREEN (2475 3950);
DISPLAY INVISIBLE (2475 3950);
FORCEPROP 1 LAST COMMENT_BODY TRUE
J 0
(2105 3980);
DISPLAY 0.872340 (2105 3980);
PAINT PEACH (2105 3980);
DISPLAY INVISIBLE (2105 3980);
FORCEPROP 2 LAST PATH I10
J 0
(2450 4150);
DISPLAY 1.021277 (2450 4150);
PAINT ORANGE (2450 4150);
DISPLAY INVISIBLE (2450 4150);
FORCEADD TAP..6
R 2
(1200 3975);
FORCEPROP 3 LASTPIN (1150 3975) SIG_NAME DMI_CPU0_PCH_RX_C_DN<3>
J 0
(1160 3985);
DISPLAY 0.659574 (1160 3985);
PAINT MONO (1160 3985);
DISPLAY INVISIBLE (1160 3985);
FORCEPROP 1 LASTPIN (1150 3975) BN 3
J 2
(1202 3983);
DISPLAY 0.617021 (1202 3983);
PAINT VIOLET (1202 3983);
FORCEPROP 2 LAST BOM_COST SB
J 0
(1175 4025);
DISPLAY 0.744681 (1175 4025);
PAINT MONO (1175 4025);
DISPLAY INVISIBLE (1175 4025);
FORCEPROP 2 LAST CDS_LIB mstr_standard
J 0
(1200 3975);
PAINT ORANGE (1200 3975);
DISPLAY INVISIBLE (1200 3975);
FORCEPROP 1 LAST BODY_TYPE PLUMBING
J 2
(1200 3925);
DISPLAY 0.872340 (1200 3925);
PAINT GREEN (1200 3925);
DISPLAY INVISIBLE (1200 3925);
FORCEPROP 1 LAST HDL_TAP TRUE
J 2
(875 3850);
DISPLAY 0.872340 (875 3850);
PAINT ORANGE (875 3850);
DISPLAY INVISIBLE (875 3850);
FORCEPROP 1 LAST PATH I11
J 2
(1202 3975);
DISPLAY 0.872340 (1202 3975);
PAINT GREEN (1202 3975);
DISPLAY INVISIBLE (1202 3975);
FORCEADD TAP..6
R 2
(1200 3775);
FORCEPROP 3 LASTPIN (1150 3775) SIG_NAME DMI_CPU0_PCH_RX_C_DN<2>
J 0
(1160 3785);
DISPLAY 0.659574 (1160 3785);
PAINT MONO (1160 3785);
DISPLAY INVISIBLE (1160 3785);
FORCEPROP 1 LASTPIN (1150 3775) BN 2
J 2
(1202 3783);
DISPLAY 0.617021 (1202 3783);
PAINT VIOLET (1202 3783);
FORCEPROP 2 LAST BOM_COST SB
J 0
(1175 3825);
DISPLAY 0.744681 (1175 3825);
PAINT MONO (1175 3825);
DISPLAY INVISIBLE (1175 3825);
FORCEPROP 2 LAST CDS_LIB mstr_standard
J 0
(1200 3775);
PAINT ORANGE (1200 3775);
DISPLAY INVISIBLE (1200 3775);
FORCEPROP 1 LAST BODY_TYPE PLUMBING
J 2
(1200 3725);
DISPLAY 0.872340 (1200 3725);
PAINT GREEN (1200 3725);
DISPLAY INVISIBLE (1200 3725);
FORCEPROP 1 LAST HDL_TAP TRUE
J 2
(875 3650);
DISPLAY 0.872340 (875 3650);
PAINT ORANGE (875 3650);
DISPLAY INVISIBLE (875 3650);
FORCEPROP 1 LAST PATH I12
J 2
(1202 3775);
DISPLAY 0.872340 (1202 3775);
PAINT GREEN (1202 3775);
DISPLAY INVISIBLE (1202 3775);
FORCEADD TAP..6
R 2
(1200 3375);
FORCEPROP 3 LASTPIN (1150 3375) SIG_NAME DMI_CPU0_PCH_RX_C_DN<0>
J 0
(1160 3385);
DISPLAY 0.659574 (1160 3385);
PAINT MONO (1160 3385);
DISPLAY INVISIBLE (1160 3385);
FORCEPROP 1 LASTPIN (1150 3375) BN 0
J 2
(1202 3383);
DISPLAY 0.617021 (1202 3383);
PAINT VIOLET (1202 3383);
FORCEPROP 2 LAST BOM_COST SB
J 0
(1175 3425);
DISPLAY 0.744681 (1175 3425);
PAINT MONO (1175 3425);
DISPLAY INVISIBLE (1175 3425);
FORCEPROP 2 LAST CDS_LIB mstr_standard
J 0
(1200 3375);
PAINT ORANGE (1200 3375);
DISPLAY INVISIBLE (1200 3375);
FORCEPROP 1 LAST BODY_TYPE PLUMBING
J 2
(1200 3325);
DISPLAY 0.872340 (1200 3325);
PAINT GREEN (1200 3325);
DISPLAY INVISIBLE (1200 3325);
FORCEPROP 1 LAST HDL_TAP TRUE
J 2
(875 3250);
DISPLAY 0.872340 (875 3250);
PAINT ORANGE (875 3250);
DISPLAY INVISIBLE (875 3250);
FORCEPROP 1 LAST PATH I13
J 2
(1202 3375);
DISPLAY 0.872340 (1202 3375);
PAINT GREEN (1202 3375);
DISPLAY INVISIBLE (1202 3375);
FORCEADD TAP..6
R 2
(1200 3575);
FORCEPROP 3 LASTPIN (1150 3575) SIG_NAME DMI_CPU0_PCH_RX_C_DN<1>
J 0
(1160 3585);
DISPLAY 0.659574 (1160 3585);
PAINT MONO (1160 3585);
DISPLAY INVISIBLE (1160 3585);
FORCEPROP 1 LASTPIN (1150 3575) BN 1
J 2
(1202 3583);
DISPLAY 0.617021 (1202 3583);
PAINT VIOLET (1202 3583);
FORCEPROP 2 LAST BOM_COST SB
J 0
(1175 3625);
DISPLAY 0.744681 (1175 3625);
PAINT MONO (1175 3625);
DISPLAY INVISIBLE (1175 3625);
FORCEPROP 2 LAST CDS_LIB mstr_standard
J 0
(1200 3575);
PAINT ORANGE (1200 3575);
DISPLAY INVISIBLE (1200 3575);
FORCEPROP 1 LAST BODY_TYPE PLUMBING
J 2
(1200 3525);
DISPLAY 0.872340 (1200 3525);
PAINT GREEN (1200 3525);
DISPLAY INVISIBLE (1200 3525);
FORCEPROP 1 LAST HDL_TAP TRUE
J 2
(875 3450);
DISPLAY 0.872340 (875 3450);
PAINT ORANGE (875 3450);
DISPLAY INVISIBLE (875 3450);
FORCEPROP 1 LAST PATH I14
J 2
(1202 3575);
DISPLAY 0.872340 (1202 3575);
PAINT GREEN (1202 3575);
DISPLAY INVISIBLE (1202 3575);
FORCEADD TAP..6
R 2
(1200 4925);
FORCEPROP 3 LASTPIN (1150 4925) SIG_NAME DMI_CPU0_PCH_TX_C_DN<3>
J 0
(1160 4935);
DISPLAY 0.659574 (1160 4935);
PAINT MONO (1160 4935);
DISPLAY INVISIBLE (1160 4935);
FORCEPROP 1 LASTPIN (1150 4925) BN 3
J 2
(1202 4933);
DISPLAY 0.617021 (1202 4933);
PAINT VIOLET (1202 4933);
FORCEPROP 2 LAST BOM_COST SB
J 0
(1175 4975);
DISPLAY 0.744681 (1175 4975);
PAINT MONO (1175 4975);
DISPLAY INVISIBLE (1175 4975);
FORCEPROP 2 LAST CDS_LIB mstr_standard
J 0
(1200 4925);
PAINT ORANGE (1200 4925);
DISPLAY INVISIBLE (1200 4925);
FORCEPROP 1 LAST BODY_TYPE PLUMBING
J 2
(1200 4875);
DISPLAY 0.872340 (1200 4875);
PAINT GREEN (1200 4875);
DISPLAY INVISIBLE (1200 4875);
FORCEPROP 1 LAST HDL_TAP TRUE
J 2
(875 4800);
DISPLAY 0.872340 (875 4800);
PAINT GREEN (875 4800);
DISPLAY INVISIBLE (875 4800);
FORCEPROP 1 LAST PATH I2
J 2
(1202 4925);
DISPLAY 0.872340 (1202 4925);
PAINT GREEN (1202 4925);
DISPLAY INVISIBLE (1202 4925);
FORCEADD TAP..1
R 2
(-125 4925);
FORCEPROP 3 LASTPIN (-75 4925) SIG_NAME DMI_CPU0_PCH_TX_DN<3>
J 0
(-65 4935);
DISPLAY 0.659574 (-65 4935);
PAINT MONO (-65 4935);
DISPLAY INVISIBLE (-65 4935);
FORCEPROP 1 LASTPIN (-75 4925) BN 3
J 2
(-63 4933);
DISPLAY 0.617021 (-63 4933);
PAINT VIOLET (-63 4933);
FORCEPROP 2 LAST BOM_COST SB
J 0
(-150 4975);
DISPLAY 0.744681 (-150 4975);
PAINT MONO (-150 4975);
DISPLAY INVISIBLE (-150 4975);
FORCEPROP 2 LAST CDS_LIB mstr_standard
J 0
(-125 4925);
PAINT ORANGE (-125 4925);
DISPLAY INVISIBLE (-125 4925);
FORCEPROP 1 LAST BODY_TYPE PLUMBING
J 2
(-125 4975);
DISPLAY 1.085106 (-125 4975);
PAINT GREEN (-125 4975);
DISPLAY INVISIBLE (-125 4975);
FORCEPROP 1 LAST HDL_TAP TRUE
J 2
(-450 4800);
DISPLAY 1.085106 (-450 4800);
PAINT GREEN (-450 4800);
DISPLAY INVISIBLE (-450 4800);
FORCEPROP 1 LAST PATH I23
J 2
(-123 4925);
DISPLAY 0.872340 (-123 4925);
PAINT GREEN (-123 4925);
DISPLAY INVISIBLE (-123 4925);
FORCEADD TAP..1
R 2
(-125 4725);
FORCEPROP 3 LASTPIN (-75 4725) SIG_NAME DMI_CPU0_PCH_TX_DN<2>
J 0
(-65 4735);
DISPLAY 0.659574 (-65 4735);
PAINT MONO (-65 4735);
DISPLAY INVISIBLE (-65 4735);
FORCEPROP 1 LASTPIN (-75 4725) BN 2
J 2
(-63 4733);
DISPLAY 0.617021 (-63 4733);
PAINT VIOLET (-63 4733);
FORCEPROP 2 LAST BOM_COST SB
J 0
(-150 4775);
DISPLAY 0.744681 (-150 4775);
PAINT MONO (-150 4775);
DISPLAY INVISIBLE (-150 4775);
FORCEPROP 2 LAST CDS_LIB mstr_standard
J 0
(-125 4725);
PAINT ORANGE (-125 4725);
DISPLAY INVISIBLE (-125 4725);
FORCEPROP 1 LAST BODY_TYPE PLUMBING
J 2
(-125 4775);
DISPLAY 1.085106 (-125 4775);
PAINT GREEN (-125 4775);
DISPLAY INVISIBLE (-125 4775);
FORCEPROP 1 LAST HDL_TAP TRUE
J 2
(-450 4600);
DISPLAY 1.085106 (-450 4600);
PAINT GREEN (-450 4600);
DISPLAY INVISIBLE (-450 4600);
FORCEPROP 1 LAST PATH I24
J 2
(-123 4725);
DISPLAY 0.872340 (-123 4725);
PAINT GREEN (-123 4725);
DISPLAY INVISIBLE (-123 4725);
FORCEADD TAP..1
R 2
(-125 4525);
FORCEPROP 3 LASTPIN (-75 4525) SIG_NAME DMI_CPU0_PCH_TX_DN<1>
J 0
(-65 4535);
DISPLAY 0.659574 (-65 4535);
PAINT MONO (-65 4535);
DISPLAY INVISIBLE (-65 4535);
FORCEPROP 1 LASTPIN (-75 4525) BN 1
J 2
(-63 4533);
DISPLAY 0.617021 (-63 4533);
PAINT VIOLET (-63 4533);
FORCEPROP 2 LAST BOM_COST SB
J 0
(-150 4575);
DISPLAY 0.744681 (-150 4575);
PAINT MONO (-150 4575);
DISPLAY INVISIBLE (-150 4575);
FORCEPROP 2 LAST CDS_LIB mstr_standard
J 0
(-125 4525);
PAINT ORANGE (-125 4525);
DISPLAY INVISIBLE (-125 4525);
FORCEPROP 1 LAST BODY_TYPE PLUMBING
J 2
(-125 4575);
DISPLAY 1.085106 (-125 4575);
PAINT GREEN (-125 4575);
DISPLAY INVISIBLE (-125 4575);
FORCEPROP 1 LAST HDL_TAP TRUE
J 2
(-450 4400);
DISPLAY 1.085106 (-450 4400);
PAINT GREEN (-450 4400);
DISPLAY INVISIBLE (-450 4400);
FORCEPROP 1 LAST PATH I25
J 2
(-123 4525);
DISPLAY 0.872340 (-123 4525);
PAINT GREEN (-123 4525);
DISPLAY INVISIBLE (-123 4525);
FORCEADD TAP..1
R 2
(-125 4325);
FORCEPROP 3 LASTPIN (-75 4325) SIG_NAME DMI_CPU0_PCH_TX_DN<0>
J 0
(-65 4335);
DISPLAY 0.659574 (-65 4335);
PAINT MONO (-65 4335);
DISPLAY INVISIBLE (-65 4335);
FORCEPROP 1 LASTPIN (-75 4325) BN 0
J 2
(-63 4333);
DISPLAY 0.617021 (-63 4333);
PAINT VIOLET (-63 4333);
FORCEPROP 2 LAST BOM_COST SB
J 0
(-150 4375);
DISPLAY 0.744681 (-150 4375);
PAINT MONO (-150 4375);
DISPLAY INVISIBLE (-150 4375);
FORCEPROP 2 LAST CDS_LIB mstr_standard
J 0
(-125 4325);
PAINT ORANGE (-125 4325);
DISPLAY INVISIBLE (-125 4325);
FORCEPROP 1 LAST BODY_TYPE PLUMBING
J 2
(-125 4375);
DISPLAY 1.085106 (-125 4375);
PAINT GREEN (-125 4375);
DISPLAY INVISIBLE (-125 4375);
FORCEPROP 1 LAST HDL_TAP TRUE
J 2
(-450 4200);
DISPLAY 1.085106 (-450 4200);
PAINT GREEN (-450 4200);
DISPLAY INVISIBLE (-450 4200);
FORCEPROP 1 LAST PATH I26
J 2
(-123 4325);
DISPLAY 0.872340 (-123 4325);
PAINT GREEN (-123 4325);
DISPLAY INVISIBLE (-123 4325);
FORCEADD OFFPAGE..1
(-1000 5025);
FORCEPROP 2 LAST $XR0 29 
J 0
(-1251 5025);
DISPLAY 0.638298 (-1251 5025);
PAINT MONO (-1251 5025);
FORCEPROP 2 LAST BOM_COST SB
J 0
(-1250 5075);
DISPLAY 0.744681 (-1250 5075);
PAINT MONO (-1250 5075);
DISPLAY INVISIBLE (-1250 5075);
FORCEPROP 2 LAST CDS_LIB mstr_standard
J 0
(-1000 5025);
PAINT ORANGE (-1000 5025);
DISPLAY INVISIBLE (-1000 5025);
FORCEPROP 1 LAST OFFPAGE TRUE
J 0
(-675 4900);
DISPLAY 1.085106 (-675 4900);
PAINT GREEN (-675 4900);
DISPLAY INVISIBLE (-675 4900);
FORCEPROP 1 LAST COMMENT_BODY TRUE
J 0
(-875 4925);
DISPLAY 1.085106 (-875 4925);
PAINT PEACH (-875 4925);
DISPLAY INVISIBLE (-875 4925);
FORCEPROP 2 LAST PATH I27
J 0
(-1250 5100);
DISPLAY 1.021277 (-1250 5100);
PAINT ORANGE (-1250 5100);
DISPLAY INVISIBLE (-1250 5100);
FORCEADD OFFPAGE..2
(-1900 5025);
FORCEPROP 2 LAST $XR0 117 
J 0
(-1711 5025);
DISPLAY 0.638298 (-1711 5025);
PAINT MONO (-1711 5025);
FORCEPROP 2 LAST BOM_COST SB
J 0
(-1575 5075);
DISPLAY 0.744681 (-1575 5075);
PAINT MONO (-1575 5075);
DISPLAY INVISIBLE (-1575 5075);
FORCEPROP 2 LAST CDS_LIB mstr_standard
J 0
(-1900 5025);
PAINT ORANGE (-1900 5025);
DISPLAY INVISIBLE (-1900 5025);
FORCEPROP 1 LAST OFFPAGE TRUE
J 0
(-1575 4900);
DISPLAY 0.872340 (-1575 4900);
PAINT GREEN (-1575 4900);
DISPLAY INVISIBLE (-1575 4900);
FORCEPROP 1 LAST COMMENT_BODY TRUE
J 0
(-1945 4930);
DISPLAY 0.872340 (-1945 4930);
PAINT PEACH (-1945 4930);
DISPLAY INVISIBLE (-1945 4930);
FORCEPROP 2 LAST PATH I28
J 0
(-1550 5100);
DISPLAY 1.021277 (-1550 5100);
PAINT ORANGE (-1550 5100);
DISPLAY INVISIBLE (-1550 5100);
FORCEADD TAP..6
R 2
(-2800 4925);
FORCEPROP 3 LASTPIN (-2850 4925) SIG_NAME DMI_CPU0_PCH_TX_C_DP<3>
J 0
(-2840 4935);
DISPLAY 0.659574 (-2840 4935);
PAINT MONO (-2840 4935);
DISPLAY INVISIBLE (-2840 4935);
FORCEPROP 1 LASTPIN (-2850 4925) BN 3
J 2
(-2798 4933);
DISPLAY 0.617021 (-2798 4933);
PAINT VIOLET (-2798 4933);
FORCEPROP 2 LAST BOM_COST SB
J 0
(-2825 4975);
DISPLAY 0.744681 (-2825 4975);
PAINT MONO (-2825 4975);
DISPLAY INVISIBLE (-2825 4975);
FORCEPROP 2 LAST CDS_LIB mstr_standard
J 0
(-2800 4925);
PAINT ORANGE (-2800 4925);
DISPLAY INVISIBLE (-2800 4925);
FORCEPROP 1 LAST BODY_TYPE PLUMBING
J 2
(-2800 4875);
DISPLAY 0.872340 (-2800 4875);
PAINT GREEN (-2800 4875);
DISPLAY INVISIBLE (-2800 4875);
FORCEPROP 1 LAST HDL_TAP TRUE
J 2
(-3125 4800);
DISPLAY 0.872340 (-3125 4800);
PAINT GREEN (-3125 4800);
DISPLAY INVISIBLE (-3125 4800);
FORCEPROP 1 LAST PATH I29
J 2
(-2798 4925);
DISPLAY 0.872340 (-2798 4925);
PAINT GREEN (-2798 4925);
DISPLAY INVISIBLE (-2798 4925);
FORCEADD TAP..6
R 2
(1200 4725);
FORCEPROP 3 LASTPIN (1150 4725) SIG_NAME DMI_CPU0_PCH_TX_C_DN<2>
J 0
(1160 4735);
DISPLAY 0.659574 (1160 4735);
PAINT MONO (1160 4735);
DISPLAY INVISIBLE (1160 4735);
FORCEPROP 1 LASTPIN (1150 4725) BN 2
J 2
(1202 4733);
DISPLAY 0.617021 (1202 4733);
PAINT VIOLET (1202 4733);
FORCEPROP 2 LAST BOM_COST SB
J 0
(1175 4775);
DISPLAY 0.744681 (1175 4775);
PAINT MONO (1175 4775);
DISPLAY INVISIBLE (1175 4775);
FORCEPROP 2 LAST CDS_LIB mstr_standard
J 0
(1200 4725);
PAINT ORANGE (1200 4725);
DISPLAY INVISIBLE (1200 4725);
FORCEPROP 1 LAST BODY_TYPE PLUMBING
J 2
(1200 4675);
DISPLAY 0.872340 (1200 4675);
PAINT GREEN (1200 4675);
DISPLAY INVISIBLE (1200 4675);
FORCEPROP 1 LAST HDL_TAP TRUE
J 2
(875 4600);
DISPLAY 0.872340 (875 4600);
PAINT GREEN (875 4600);
DISPLAY INVISIBLE (875 4600);
FORCEPROP 1 LAST PATH I3
J 2
(1202 4725);
DISPLAY 0.872340 (1202 4725);
PAINT GREEN (1202 4725);
DISPLAY INVISIBLE (1202 4725);
FORCEADD TAP..6
R 2
(-2800 4725);
FORCEPROP 3 LASTPIN (-2850 4725) SIG_NAME DMI_CPU0_PCH_TX_C_DP<2>
J 0
(-2840 4735);
DISPLAY 0.659574 (-2840 4735);
PAINT MONO (-2840 4735);
DISPLAY INVISIBLE (-2840 4735);
FORCEPROP 1 LASTPIN (-2850 4725) BN 2
J 2
(-2798 4733);
DISPLAY 0.617021 (-2798 4733);
PAINT VIOLET (-2798 4733);
FORCEPROP 2 LAST BOM_COST SB
J 0
(-2825 4775);
DISPLAY 0.744681 (-2825 4775);
PAINT MONO (-2825 4775);
DISPLAY INVISIBLE (-2825 4775);
FORCEPROP 2 LAST CDS_LIB mstr_standard
J 0
(-2800 4725);
PAINT ORANGE (-2800 4725);
DISPLAY INVISIBLE (-2800 4725);
FORCEPROP 1 LAST BODY_TYPE PLUMBING
J 2
(-2800 4675);
DISPLAY 0.872340 (-2800 4675);
PAINT GREEN (-2800 4675);
DISPLAY INVISIBLE (-2800 4675);
FORCEPROP 1 LAST HDL_TAP TRUE
J 2
(-3125 4600);
DISPLAY 0.872340 (-3125 4600);
PAINT GREEN (-3125 4600);
DISPLAY INVISIBLE (-3125 4600);
FORCEPROP 1 LAST PATH I30
J 2
(-2798 4725);
DISPLAY 0.872340 (-2798 4725);
PAINT GREEN (-2798 4725);
DISPLAY INVISIBLE (-2798 4725);
FORCEADD TAP..6
R 2
(-2800 4525);
FORCEPROP 3 LASTPIN (-2850 4525) SIG_NAME DMI_CPU0_PCH_TX_C_DP<1>
J 0
(-2840 4535);
DISPLAY 0.659574 (-2840 4535);
PAINT MONO (-2840 4535);
DISPLAY INVISIBLE (-2840 4535);
FORCEPROP 1 LASTPIN (-2850 4525) BN 1
J 2
(-2798 4533);
DISPLAY 0.617021 (-2798 4533);
PAINT VIOLET (-2798 4533);
FORCEPROP 2 LAST BOM_COST SB
J 0
(-2825 4575);
DISPLAY 0.744681 (-2825 4575);
PAINT MONO (-2825 4575);
DISPLAY INVISIBLE (-2825 4575);
FORCEPROP 2 LAST CDS_LIB mstr_standard
J 0
(-2800 4525);
PAINT ORANGE (-2800 4525);
DISPLAY INVISIBLE (-2800 4525);
FORCEPROP 1 LAST BODY_TYPE PLUMBING
J 2
(-2800 4475);
DISPLAY 0.872340 (-2800 4475);
PAINT GREEN (-2800 4475);
DISPLAY INVISIBLE (-2800 4475);
FORCEPROP 1 LAST HDL_TAP TRUE
J 2
(-3125 4400);
DISPLAY 0.872340 (-3125 4400);
PAINT GREEN (-3125 4400);
DISPLAY INVISIBLE (-3125 4400);
FORCEPROP 1 LAST PATH I31
J 2
(-2798 4525);
DISPLAY 0.872340 (-2798 4525);
PAINT GREEN (-2798 4525);
DISPLAY INVISIBLE (-2798 4525);
FORCEADD TAP..6
R 2
(-2800 4325);
FORCEPROP 3 LASTPIN (-2850 4325) SIG_NAME DMI_CPU0_PCH_TX_C_DP<0>
J 0
(-2840 4335);
DISPLAY 0.659574 (-2840 4335);
PAINT MONO (-2840 4335);
DISPLAY INVISIBLE (-2840 4335);
FORCEPROP 1 LASTPIN (-2850 4325) BN 0
J 2
(-2798 4333);
DISPLAY 0.617021 (-2798 4333);
PAINT VIOLET (-2798 4333);
FORCEPROP 2 LAST BOM_COST SB
J 0
(-2825 4375);
DISPLAY 0.744681 (-2825 4375);
PAINT MONO (-2825 4375);
DISPLAY INVISIBLE (-2825 4375);
FORCEPROP 2 LAST CDS_LIB mstr_standard
J 0
(-2800 4325);
PAINT ORANGE (-2800 4325);
DISPLAY INVISIBLE (-2800 4325);
FORCEPROP 1 LAST BODY_TYPE PLUMBING
J 2
(-2800 4275);
DISPLAY 0.872340 (-2800 4275);
PAINT GREEN (-2800 4275);
DISPLAY INVISIBLE (-2800 4275);
FORCEPROP 1 LAST HDL_TAP TRUE
J 2
(-3125 4200);
DISPLAY 0.872340 (-3125 4200);
PAINT GREEN (-3125 4200);
DISPLAY INVISIBLE (-3125 4200);
FORCEPROP 1 LAST PATH I32
J 2
(-2798 4325);
DISPLAY 0.872340 (-2798 4325);
PAINT GREEN (-2798 4325);
DISPLAY INVISIBLE (-2798 4325);
FORCEADD CAP..1
R 1
(-3650 4925);
FORCEPROP 1 LAST LOCATION C7B25
J 0
(-3725 5025);
DISPLAY 0.617021 (-3725 5025);
PAINT AQUA (-3725 5025);
FORCEPROP 1 LAST PART_NUMBER A36096-155
J 0
(-3800 4975);
DISPLAY 0.617021 (-3800 4975);
PAINT BLUE (-3800 4975);
FORCEPROP 1 LAST VALUE 0.22UF
J 0
(-3850 4875);
DISPLAY 0.617021 (-3850 4875);
PAINT SKYBLUE (-3850 4875);
FORCEPROP 1 LAST TOLERANCE 10%
J 0
(-3825 4825);
DISPLAY 0.617021 (-3825 4825);
PAINT SKYBLUE (-3825 4825);
FORCEPROP 1 LAST PACK_TYPE 0402
J 0
(-3825 4775);
DISPLAY 0.617021 (-3825 4775);
PAINT SKYBLUE (-3825 4775);
FORCEPROP 1 LAST MATERIAL X7R
J 0
(-3600 4825);
DISPLAY 0.617021 (-3600 4825);
PAINT SKYBLUE (-3600 4825);
FORCEPROP 1 LASTPIN (-3550 4925) $PN 2
J 0
(-3580 4935);
DISPLAY 0.617021 (-3580 4935);
PAINT WHITE (-3580 4935);
FORCEPROP 1 LASTPIN (-3750 4925) $PN 1
J 0
(-3755 4935);
DISPLAY 0.617021 (-3755 4935);
PAINT WHITE (-3755 4935);
FORCEPROP 1 LAST VOLTAGE 16V
J 0
(-3600 4875);
DISPLAY 0.510638 (-3600 4875);
PAINT SKYBLUE (-3600 4875);
DISPLAY INVISIBLE (-3600 4875);
FORCEPROP 2 LAST BOM_COST SB
J 0
(-3725 5075);
DISPLAY 0.744681 (-3725 5075);
PAINT MONO (-3725 5075);
DISPLAY INVISIBLE (-3725 5075);
FORCEPROP 2 LAST CDS_LIB mstr_discrete
J 0
(-3650 4925);
PAINT ORANGE (-3650 4925);
DISPLAY INVISIBLE (-3650 4925);
FORCEPROP 2 LAST CDS_SEC 1
J 0
(-3525 5225);
PAINT MONO (-3525 5225);
DISPLAY INVISIBLE (-3525 5225);
FORCEPROP 2 LAST $SEC 1
J 0
(-3525 5225);
PAINT MONO (-3525 5225);
DISPLAY INVISIBLE (-3525 5225);
FORCEPROP 2 LAST CDS_LOCATION C7B25
J 0
(-3725 5025);
DISPLAY 0.617021 (-3725 5025);
PAINT AQUA (-3725 5025);
DISPLAY INVISIBLE (-3725 5025);
FORCEPROP 1 LAST PATH I35
R 1
J 0
(-3800 4975);
DISPLAY 0.978723 (-3800 4975);
PAINT WHITE (-3800 4975);
DISPLAY INVISIBLE (-3800 4975);
FORCEPROP 2 LAST ROOM DMI
J 0
(-3525 5225);
PAINT ORANGE (-3525 5225);
DISPLAY INVISIBLE (-3525 5225);
FORCEADD TAP..1
R 2
(-150 3975);
FORCEPROP 3 LASTPIN (-100 3975) SIG_NAME DMI_CPU0_PCH_RX_DN<3>
J 0
(-90 3985);
DISPLAY 0.659574 (-90 3985);
PAINT MONO (-90 3985);
DISPLAY INVISIBLE (-90 3985);
FORCEPROP 1 LASTPIN (-100 3975) BN 3
J 2
(-88 3983);
DISPLAY 0.617021 (-88 3983);
PAINT VIOLET (-88 3983);
FORCEPROP 2 LAST BOM_COST SB
J 0
(-175 4025);
DISPLAY 0.744681 (-175 4025);
PAINT MONO (-175 4025);
DISPLAY INVISIBLE (-175 4025);
FORCEPROP 2 LAST CDS_LIB mstr_standard
J 0
(-150 3975);
PAINT ORANGE (-150 3975);
DISPLAY INVISIBLE (-150 3975);
FORCEPROP 1 LAST BODY_TYPE PLUMBING
J 2
(-150 4025);
DISPLAY 1.085106 (-150 4025);
PAINT GREEN (-150 4025);
DISPLAY INVISIBLE (-150 4025);
FORCEPROP 1 LAST HDL_TAP TRUE
J 2
(-475 3850);
DISPLAY 1.085106 (-475 3850);
PAINT GREEN (-475 3850);
DISPLAY INVISIBLE (-475 3850);
FORCEPROP 1 LAST PATH I37
J 2
(-148 3975);
DISPLAY 0.872340 (-148 3975);
PAINT GREEN (-148 3975);
DISPLAY INVISIBLE (-148 3975);
FORCEADD TAP..1
R 2
(-150 3775);
FORCEPROP 3 LASTPIN (-100 3775) SIG_NAME DMI_CPU0_PCH_RX_DN<2>
J 0
(-90 3785);
DISPLAY 0.659574 (-90 3785);
PAINT MONO (-90 3785);
DISPLAY INVISIBLE (-90 3785);
FORCEPROP 1 LASTPIN (-100 3775) BN 2
J 2
(-88 3783);
DISPLAY 0.617021 (-88 3783);
PAINT VIOLET (-88 3783);
FORCEPROP 2 LAST BOM_COST SB
J 0
(-175 3825);
DISPLAY 0.744681 (-175 3825);
PAINT MONO (-175 3825);
DISPLAY INVISIBLE (-175 3825);
FORCEPROP 2 LAST CDS_LIB mstr_standard
J 0
(-150 3775);
PAINT ORANGE (-150 3775);
DISPLAY INVISIBLE (-150 3775);
FORCEPROP 1 LAST BODY_TYPE PLUMBING
J 2
(-150 3825);
DISPLAY 1.085106 (-150 3825);
PAINT GREEN (-150 3825);
DISPLAY INVISIBLE (-150 3825);
FORCEPROP 1 LAST HDL_TAP TRUE
J 2
(-475 3650);
DISPLAY 1.085106 (-475 3650);
PAINT GREEN (-475 3650);
DISPLAY INVISIBLE (-475 3650);
FORCEPROP 1 LAST PATH I38
J 2
(-148 3775);
DISPLAY 0.872340 (-148 3775);
PAINT GREEN (-148 3775);
DISPLAY INVISIBLE (-148 3775);
FORCEADD TAP..1
R 2
(-150 3375);
FORCEPROP 3 LASTPIN (-100 3375) SIG_NAME DMI_CPU0_PCH_RX_DN<0>
J 0
(-90 3385);
DISPLAY 0.659574 (-90 3385);
PAINT MONO (-90 3385);
DISPLAY INVISIBLE (-90 3385);
FORCEPROP 1 LASTPIN (-100 3375) BN 0
J 2
(-88 3383);
DISPLAY 0.617021 (-88 3383);
PAINT VIOLET (-88 3383);
FORCEPROP 2 LAST BOM_COST SB
J 0
(-175 3425);
DISPLAY 0.744681 (-175 3425);
PAINT MONO (-175 3425);
DISPLAY INVISIBLE (-175 3425);
FORCEPROP 2 LAST CDS_LIB mstr_standard
J 0
(-150 3375);
PAINT ORANGE (-150 3375);
DISPLAY INVISIBLE (-150 3375);
FORCEPROP 1 LAST BODY_TYPE PLUMBING
J 2
(-150 3425);
DISPLAY 1.085106 (-150 3425);
PAINT GREEN (-150 3425);
DISPLAY INVISIBLE (-150 3425);
FORCEPROP 1 LAST HDL_TAP TRUE
J 2
(-475 3250);
DISPLAY 1.085106 (-475 3250);
PAINT GREEN (-475 3250);
DISPLAY INVISIBLE (-475 3250);
FORCEPROP 1 LAST PATH I39
J 2
(-148 3375);
DISPLAY 0.872340 (-148 3375);
PAINT GREEN (-148 3375);
DISPLAY INVISIBLE (-148 3375);
FORCEADD TAP..6
R 2
(1200 4525);
FORCEPROP 3 LASTPIN (1150 4525) SIG_NAME DMI_CPU0_PCH_TX_C_DN<1>
J 0
(1160 4535);
DISPLAY 0.659574 (1160 4535);
PAINT MONO (1160 4535);
DISPLAY INVISIBLE (1160 4535);
FORCEPROP 1 LASTPIN (1150 4525) BN 1
J 2
(1202 4533);
DISPLAY 0.617021 (1202 4533);
PAINT VIOLET (1202 4533);
FORCEPROP 2 LAST BOM_COST SB
J 0
(1175 4575);
DISPLAY 0.744681 (1175 4575);
PAINT MONO (1175 4575);
DISPLAY INVISIBLE (1175 4575);
FORCEPROP 2 LAST CDS_LIB mstr_standard
J 0
(1200 4525);
PAINT ORANGE (1200 4525);
DISPLAY INVISIBLE (1200 4525);
FORCEPROP 1 LAST BODY_TYPE PLUMBING
J 2
(1200 4475);
DISPLAY 0.872340 (1200 4475);
PAINT GREEN (1200 4475);
DISPLAY INVISIBLE (1200 4475);
FORCEPROP 1 LAST HDL_TAP TRUE
J 2
(875 4400);
DISPLAY 0.872340 (875 4400);
PAINT GREEN (875 4400);
DISPLAY INVISIBLE (875 4400);
FORCEPROP 1 LAST PATH I4
J 2
(1202 4525);
DISPLAY 0.872340 (1202 4525);
PAINT GREEN (1202 4525);
DISPLAY INVISIBLE (1202 4525);
FORCEADD TAP..1
R 2
(-150 3575);
FORCEPROP 3 LASTPIN (-100 3575) SIG_NAME DMI_CPU0_PCH_RX_DN<1>
J 0
(-90 3585);
DISPLAY 0.659574 (-90 3585);
PAINT MONO (-90 3585);
DISPLAY INVISIBLE (-90 3585);
FORCEPROP 1 LASTPIN (-100 3575) BN 1
J 2
(-88 3583);
DISPLAY 0.617021 (-88 3583);
PAINT VIOLET (-88 3583);
FORCEPROP 2 LAST BOM_COST SB
J 0
(-175 3625);
DISPLAY 0.744681 (-175 3625);
PAINT MONO (-175 3625);
DISPLAY INVISIBLE (-175 3625);
FORCEPROP 2 LAST CDS_LIB mstr_standard
J 0
(-150 3575);
PAINT ORANGE (-150 3575);
DISPLAY INVISIBLE (-150 3575);
FORCEPROP 1 LAST BODY_TYPE PLUMBING
J 2
(-150 3625);
DISPLAY 1.085106 (-150 3625);
PAINT GREEN (-150 3625);
DISPLAY INVISIBLE (-150 3625);
FORCEPROP 1 LAST HDL_TAP TRUE
J 2
(-475 3450);
DISPLAY 1.085106 (-475 3450);
PAINT GREEN (-475 3450);
DISPLAY INVISIBLE (-475 3450);
FORCEPROP 1 LAST PATH I40
J 2
(-148 3575);
DISPLAY 0.872340 (-148 3575);
PAINT GREEN (-148 3575);
DISPLAY INVISIBLE (-148 3575);
FORCEADD OFFPAGE..1
(-1000 4075);
FORCEPROP 2 LAST $XR0 117 
J 0
(-1282 4075);
DISPLAY 0.638298 (-1282 4075);
PAINT MONO (-1282 4075);
FORCEPROP 2 LAST BOM_COST SB
J 0
(-1275 4125);
DISPLAY 0.744681 (-1275 4125);
PAINT MONO (-1275 4125);
DISPLAY INVISIBLE (-1275 4125);
FORCEPROP 2 LAST CDS_LIB mstr_standard
J 0
(-1000 4075);
PAINT ORANGE (-1000 4075);
DISPLAY INVISIBLE (-1000 4075);
FORCEPROP 1 LAST OFFPAGE TRUE
J 0
(-675 3950);
DISPLAY 1.085106 (-675 3950);
PAINT GREEN (-675 3950);
DISPLAY INVISIBLE (-675 3950);
FORCEPROP 1 LAST COMMENT_BODY TRUE
J 0
(-875 3975);
DISPLAY 1.085106 (-875 3975);
PAINT PEACH (-875 3975);
DISPLAY INVISIBLE (-875 3975);
FORCEPROP 2 LAST PATH I42
J 0
(-1250 4150);
DISPLAY 1.021277 (-1250 4150);
PAINT ORANGE (-1250 4150);
DISPLAY INVISIBLE (-1250 4150);
FORCEADD OFFPAGE..2
(-1900 4075);
FORCEPROP 2 LAST $XR0 29 
J 0
(-1711 4075);
DISPLAY 0.638298 (-1711 4075);
PAINT MONO (-1711 4075);
FORCEPROP 2 LAST BOM_COST SB
J 0
(-1600 4125);
DISPLAY 0.744681 (-1600 4125);
PAINT MONO (-1600 4125);
DISPLAY INVISIBLE (-1600 4125);
FORCEPROP 2 LAST CDS_LIB mstr_standard
J 0
(-1900 4075);
PAINT ORANGE (-1900 4075);
DISPLAY INVISIBLE (-1900 4075);
FORCEPROP 1 LAST OFFPAGE TRUE
J 0
(-1575 3950);
DISPLAY 0.872340 (-1575 3950);
PAINT GREEN (-1575 3950);
DISPLAY INVISIBLE (-1575 3950);
FORCEPROP 1 LAST COMMENT_BODY TRUE
J 0
(-1945 3980);
DISPLAY 0.872340 (-1945 3980);
PAINT PEACH (-1945 3980);
DISPLAY INVISIBLE (-1945 3980);
FORCEPROP 2 LAST PATH I43
J 0
(-1600 4150);
DISPLAY 1.021277 (-1600 4150);
PAINT ORANGE (-1600 4150);
DISPLAY INVISIBLE (-1600 4150);
FORCEADD TAP..6
R 2
(-2800 3975);
FORCEPROP 3 LASTPIN (-2850 3975) SIG_NAME DMI_CPU0_PCH_RX_C_DP<3>
J 0
(-2840 3985);
DISPLAY 0.659574 (-2840 3985);
PAINT MONO (-2840 3985);
DISPLAY INVISIBLE (-2840 3985);
FORCEPROP 1 LASTPIN (-2850 3975) BN 3
J 2
(-2798 3983);
DISPLAY 0.617021 (-2798 3983);
PAINT VIOLET (-2798 3983);
FORCEPROP 2 LAST BOM_COST SB
J 0
(-2825 4025);
DISPLAY 0.744681 (-2825 4025);
PAINT MONO (-2825 4025);
DISPLAY INVISIBLE (-2825 4025);
FORCEPROP 2 LAST CDS_LIB mstr_standard
J 0
(-2800 3975);
PAINT ORANGE (-2800 3975);
DISPLAY INVISIBLE (-2800 3975);
FORCEPROP 1 LAST BODY_TYPE PLUMBING
J 2
(-2800 3925);
DISPLAY 0.872340 (-2800 3925);
PAINT GREEN (-2800 3925);
DISPLAY INVISIBLE (-2800 3925);
FORCEPROP 1 LAST HDL_TAP TRUE
J 2
(-3125 3850);
DISPLAY 0.872340 (-3125 3850);
PAINT RED (-3125 3850);
DISPLAY INVISIBLE (-3125 3850);
FORCEPROP 1 LAST PATH I45
J 2
(-2798 3975);
DISPLAY 0.872340 (-2798 3975);
PAINT GREEN (-2798 3975);
DISPLAY INVISIBLE (-2798 3975);
FORCEADD TAP..6
R 2
(-2800 3775);
FORCEPROP 3 LASTPIN (-2850 3775) SIG_NAME DMI_CPU0_PCH_RX_C_DP<2>
J 0
(-2840 3785);
DISPLAY 0.659574 (-2840 3785);
PAINT MONO (-2840 3785);
DISPLAY INVISIBLE (-2840 3785);
FORCEPROP 1 LASTPIN (-2850 3775) BN 2
J 2
(-2798 3783);
DISPLAY 0.617021 (-2798 3783);
PAINT VIOLET (-2798 3783);
FORCEPROP 2 LAST BOM_COST SB
J 0
(-2825 3825);
DISPLAY 0.744681 (-2825 3825);
PAINT MONO (-2825 3825);
DISPLAY INVISIBLE (-2825 3825);
FORCEPROP 2 LAST CDS_LIB mstr_standard
J 0
(-2800 3775);
PAINT ORANGE (-2800 3775);
DISPLAY INVISIBLE (-2800 3775);
FORCEPROP 1 LAST BODY_TYPE PLUMBING
J 2
(-2800 3725);
DISPLAY 0.872340 (-2800 3725);
PAINT GREEN (-2800 3725);
DISPLAY INVISIBLE (-2800 3725);
FORCEPROP 1 LAST HDL_TAP TRUE
J 2
(-3125 3650);
DISPLAY 0.872340 (-3125 3650);
PAINT RED (-3125 3650);
DISPLAY INVISIBLE (-3125 3650);
FORCEPROP 1 LAST PATH I46
J 2
(-2798 3775);
DISPLAY 0.872340 (-2798 3775);
PAINT GREEN (-2798 3775);
DISPLAY INVISIBLE (-2798 3775);
FORCEADD TAP..6
R 2
(-2800 3375);
FORCEPROP 3 LASTPIN (-2850 3375) SIG_NAME DMI_CPU0_PCH_RX_C_DP<0>
J 0
(-2840 3385);
DISPLAY 0.659574 (-2840 3385);
PAINT MONO (-2840 3385);
DISPLAY INVISIBLE (-2840 3385);
FORCEPROP 1 LASTPIN (-2850 3375) BN 0
J 2
(-2798 3383);
DISPLAY 0.617021 (-2798 3383);
PAINT VIOLET (-2798 3383);
FORCEPROP 2 LAST BOM_COST SB
J 0
(-2825 3425);
DISPLAY 0.744681 (-2825 3425);
PAINT MONO (-2825 3425);
DISPLAY INVISIBLE (-2825 3425);
FORCEPROP 2 LAST CDS_LIB mstr_standard
J 0
(-2800 3375);
PAINT ORANGE (-2800 3375);
DISPLAY INVISIBLE (-2800 3375);
FORCEPROP 1 LAST BODY_TYPE PLUMBING
J 2
(-2800 3325);
DISPLAY 0.872340 (-2800 3325);
PAINT GREEN (-2800 3325);
DISPLAY INVISIBLE (-2800 3325);
FORCEPROP 1 LAST HDL_TAP TRUE
J 2
(-3125 3250);
DISPLAY 0.872340 (-3125 3250);
PAINT RED (-3125 3250);
DISPLAY INVISIBLE (-3125 3250);
FORCEPROP 1 LAST PATH I47
J 2
(-2798 3375);
DISPLAY 0.872340 (-2798 3375);
PAINT GREEN (-2798 3375);
DISPLAY INVISIBLE (-2798 3375);
FORCEADD TAP..6
R 2
(-2800 3575);
FORCEPROP 3 LASTPIN (-2850 3575) SIG_NAME DMI_CPU0_PCH_RX_C_DP<1>
J 0
(-2840 3585);
DISPLAY 0.659574 (-2840 3585);
PAINT MONO (-2840 3585);
DISPLAY INVISIBLE (-2840 3585);
FORCEPROP 1 LASTPIN (-2850 3575) BN 1
J 2
(-2798 3583);
DISPLAY 0.617021 (-2798 3583);
PAINT VIOLET (-2798 3583);
FORCEPROP 2 LAST BOM_COST SB
J 0
(-2825 3625);
DISPLAY 0.744681 (-2825 3625);
PAINT MONO (-2825 3625);
DISPLAY INVISIBLE (-2825 3625);
FORCEPROP 2 LAST CDS_LIB mstr_standard
J 0
(-2800 3575);
PAINT ORANGE (-2800 3575);
DISPLAY INVISIBLE (-2800 3575);
FORCEPROP 1 LAST BODY_TYPE PLUMBING
J 2
(-2800 3525);
DISPLAY 0.872340 (-2800 3525);
PAINT GREEN (-2800 3525);
DISPLAY INVISIBLE (-2800 3525);
FORCEPROP 1 LAST HDL_TAP TRUE
J 2
(-3125 3450);
DISPLAY 0.872340 (-3125 3450);
PAINT RED (-3125 3450);
DISPLAY INVISIBLE (-3125 3450);
FORCEPROP 1 LAST PATH I48
J 2
(-2798 3575);
DISPLAY 0.872340 (-2798 3575);
PAINT GREEN (-2798 3575);
DISPLAY INVISIBLE (-2798 3575);
FORCEADD TAP..6
R 2
(1200 4325);
FORCEPROP 3 LASTPIN (1150 4325) SIG_NAME DMI_CPU0_PCH_TX_C_DN<0>
J 0
(1160 4335);
DISPLAY 0.659574 (1160 4335);
PAINT MONO (1160 4335);
DISPLAY INVISIBLE (1160 4335);
FORCEPROP 1 LASTPIN (1150 4325) BN 0
J 2
(1202 4333);
DISPLAY 0.617021 (1202 4333);
PAINT VIOLET (1202 4333);
FORCEPROP 2 LAST BOM_COST SB
J 0
(1175 4375);
DISPLAY 0.744681 (1175 4375);
PAINT MONO (1175 4375);
DISPLAY INVISIBLE (1175 4375);
FORCEPROP 2 LAST CDS_LIB mstr_standard
J 0
(1200 4325);
PAINT ORANGE (1200 4325);
DISPLAY INVISIBLE (1200 4325);
FORCEPROP 1 LAST BODY_TYPE PLUMBING
J 2
(1200 4275);
DISPLAY 0.872340 (1200 4275);
PAINT GREEN (1200 4275);
DISPLAY INVISIBLE (1200 4275);
FORCEPROP 1 LAST HDL_TAP TRUE
J 2
(875 4200);
DISPLAY 0.872340 (875 4200);
PAINT GREEN (875 4200);
DISPLAY INVISIBLE (875 4200);
FORCEPROP 1 LAST PATH I5
J 2
(1202 4325);
DISPLAY 0.872340 (1202 4325);
PAINT GREEN (1202 4325);
DISPLAY INVISIBLE (1202 4325);
FORCEADD TAP..1
R 2
(-4150 4925);
FORCEPROP 3 LASTPIN (-4100 4925) SIG_NAME DMI_CPU0_PCH_TX_DP<3>
J 0
(-4090 4935);
DISPLAY 0.659574 (-4090 4935);
PAINT MONO (-4090 4935);
DISPLAY INVISIBLE (-4090 4935);
FORCEPROP 1 LASTPIN (-4100 4925) BN 3
J 2
(-4088 4933);
DISPLAY 0.617021 (-4088 4933);
PAINT VIOLET (-4088 4933);
FORCEPROP 2 LAST BOM_COST SB
J 0
(-4175 4975);
DISPLAY 0.744681 (-4175 4975);
PAINT MONO (-4175 4975);
DISPLAY INVISIBLE (-4175 4975);
FORCEPROP 2 LAST CDS_LIB mstr_standard
J 0
(-4150 4925);
PAINT ORANGE (-4150 4925);
DISPLAY INVISIBLE (-4150 4925);
FORCEPROP 1 LAST BODY_TYPE PLUMBING
J 2
(-4150 4975);
DISPLAY 1.085106 (-4150 4975);
PAINT GREEN (-4150 4975);
DISPLAY INVISIBLE (-4150 4975);
FORCEPROP 1 LAST HDL_TAP TRUE
J 2
(-4475 4800);
DISPLAY 1.085106 (-4475 4800);
PAINT GREEN (-4475 4800);
DISPLAY INVISIBLE (-4475 4800);
FORCEPROP 1 LAST PATH I57
J 2
(-4148 4925);
DISPLAY 0.872340 (-4148 4925);
PAINT GREEN (-4148 4925);
DISPLAY INVISIBLE (-4148 4925);
FORCEADD TAP..1
R 2
(-4150 4725);
FORCEPROP 3 LASTPIN (-4100 4725) SIG_NAME DMI_CPU0_PCH_TX_DP<2>
J 0
(-4090 4735);
DISPLAY 0.659574 (-4090 4735);
PAINT MONO (-4090 4735);
DISPLAY INVISIBLE (-4090 4735);
FORCEPROP 1 LASTPIN (-4100 4725) BN 2
J 2
(-4088 4733);
DISPLAY 0.617021 (-4088 4733);
PAINT VIOLET (-4088 4733);
FORCEPROP 2 LAST BOM_COST SB
J 0
(-4175 4775);
DISPLAY 0.744681 (-4175 4775);
PAINT MONO (-4175 4775);
DISPLAY INVISIBLE (-4175 4775);
FORCEPROP 2 LAST CDS_LIB mstr_standard
J 0
(-4150 4725);
PAINT ORANGE (-4150 4725);
DISPLAY INVISIBLE (-4150 4725);
FORCEPROP 1 LAST BODY_TYPE PLUMBING
J 2
(-4150 4775);
DISPLAY 1.085106 (-4150 4775);
PAINT GREEN (-4150 4775);
DISPLAY INVISIBLE (-4150 4775);
FORCEPROP 1 LAST HDL_TAP TRUE
J 2
(-4475 4600);
DISPLAY 1.085106 (-4475 4600);
PAINT GREEN (-4475 4600);
DISPLAY INVISIBLE (-4475 4600);
FORCEPROP 1 LAST PATH I58
J 2
(-4148 4725);
DISPLAY 0.872340 (-4148 4725);
PAINT GREEN (-4148 4725);
DISPLAY INVISIBLE (-4148 4725);
FORCEADD TAP..1
R 2
(-4150 4525);
FORCEPROP 3 LASTPIN (-4100 4525) SIG_NAME DMI_CPU0_PCH_TX_DP<1>
J 0
(-4090 4535);
DISPLAY 0.659574 (-4090 4535);
PAINT MONO (-4090 4535);
DISPLAY INVISIBLE (-4090 4535);
FORCEPROP 1 LASTPIN (-4100 4525) BN 1
J 2
(-4088 4533);
DISPLAY 0.617021 (-4088 4533);
PAINT VIOLET (-4088 4533);
FORCEPROP 2 LAST BOM_COST SB
J 0
(-4175 4575);
DISPLAY 0.744681 (-4175 4575);
PAINT MONO (-4175 4575);
DISPLAY INVISIBLE (-4175 4575);
FORCEPROP 2 LAST CDS_LIB mstr_standard
J 0
(-4150 4525);
PAINT ORANGE (-4150 4525);
DISPLAY INVISIBLE (-4150 4525);
FORCEPROP 1 LAST BODY_TYPE PLUMBING
J 2
(-4150 4575);
DISPLAY 1.085106 (-4150 4575);
PAINT GREEN (-4150 4575);
DISPLAY INVISIBLE (-4150 4575);
FORCEPROP 1 LAST HDL_TAP TRUE
J 2
(-4475 4400);
DISPLAY 1.085106 (-4475 4400);
PAINT GREEN (-4475 4400);
DISPLAY INVISIBLE (-4475 4400);
FORCEPROP 1 LAST PATH I59
J 2
(-4148 4525);
DISPLAY 0.872340 (-4148 4525);
PAINT GREEN (-4148 4525);
DISPLAY INVISIBLE (-4148 4525);
FORCEADD TAP..1
R 2
(-4150 4325);
FORCEPROP 3 LASTPIN (-4100 4325) SIG_NAME DMI_CPU0_PCH_TX_DP<0>
J 0
(-4090 4335);
DISPLAY 0.659574 (-4090 4335);
PAINT MONO (-4090 4335);
DISPLAY INVISIBLE (-4090 4335);
FORCEPROP 1 LASTPIN (-4100 4325) BN 0
J 2
(-4088 4333);
DISPLAY 0.617021 (-4088 4333);
PAINT VIOLET (-4088 4333);
FORCEPROP 2 LAST BOM_COST SB
J 0
(-4175 4375);
DISPLAY 0.744681 (-4175 4375);
PAINT MONO (-4175 4375);
DISPLAY INVISIBLE (-4175 4375);
FORCEPROP 2 LAST CDS_LIB mstr_standard
J 0
(-4150 4325);
PAINT ORANGE (-4150 4325);
DISPLAY INVISIBLE (-4150 4325);
FORCEPROP 1 LAST BODY_TYPE PLUMBING
J 2
(-4150 4375);
DISPLAY 1.085106 (-4150 4375);
PAINT GREEN (-4150 4375);
DISPLAY INVISIBLE (-4150 4375);
FORCEPROP 1 LAST HDL_TAP TRUE
J 2
(-4475 4200);
DISPLAY 1.085106 (-4475 4200);
PAINT GREEN (-4475 4200);
DISPLAY INVISIBLE (-4475 4200);
FORCEPROP 1 LAST PATH I60
J 2
(-4148 4325);
DISPLAY 0.872340 (-4148 4325);
PAINT GREEN (-4148 4325);
DISPLAY INVISIBLE (-4148 4325);
FORCEADD OFFPAGE..1
(-5050 5025);
FORCEPROP 2 LAST $XR0 29 
J 0
(-5301 5025);
DISPLAY 0.638298 (-5301 5025);
PAINT MONO (-5301 5025);
FORCEPROP 2 LAST BOM_COST SB
J 0
(-5300 5075);
DISPLAY 0.744681 (-5300 5075);
PAINT MONO (-5300 5075);
DISPLAY INVISIBLE (-5300 5075);
FORCEPROP 2 LAST CDS_LIB mstr_standard
J 0
(-5050 5025);
PAINT ORANGE (-5050 5025);
DISPLAY INVISIBLE (-5050 5025);
FORCEPROP 1 LAST OFFPAGE TRUE
J 0
(-4725 4900);
DISPLAY 1.085106 (-4725 4900);
PAINT GREEN (-4725 4900);
DISPLAY INVISIBLE (-4725 4900);
FORCEPROP 1 LAST COMMENT_BODY TRUE
J 0
(-4925 4925);
DISPLAY 1.085106 (-4925 4925);
PAINT PEACH (-4925 4925);
DISPLAY INVISIBLE (-4925 4925);
FORCEPROP 2 LAST PATH I61
J 0
(-5300 5100);
DISPLAY 1.021277 (-5300 5100);
PAINT ORANGE (-5300 5100);
DISPLAY INVISIBLE (-5300 5100);
FORCEADD TAP..1
R 2
(-4150 3975);
FORCEPROP 3 LASTPIN (-4100 3975) SIG_NAME DMI_CPU0_PCH_RX_DP<3>
J 0
(-4090 3985);
DISPLAY 0.659574 (-4090 3985);
PAINT MONO (-4090 3985);
DISPLAY INVISIBLE (-4090 3985);
FORCEPROP 1 LASTPIN (-4100 3975) BN 3
J 2
(-4088 3983);
DISPLAY 0.617021 (-4088 3983);
PAINT VIOLET (-4088 3983);
FORCEPROP 2 LAST BOM_COST SB
J 0
(-4175 4025);
DISPLAY 0.744681 (-4175 4025);
PAINT MONO (-4175 4025);
DISPLAY INVISIBLE (-4175 4025);
FORCEPROP 2 LAST CDS_LIB mstr_standard
J 0
(-4150 3975);
PAINT ORANGE (-4150 3975);
DISPLAY INVISIBLE (-4150 3975);
FORCEPROP 1 LAST BODY_TYPE PLUMBING
J 2
(-4150 4025);
DISPLAY 1.085106 (-4150 4025);
PAINT GREEN (-4150 4025);
DISPLAY INVISIBLE (-4150 4025);
FORCEPROP 1 LAST HDL_TAP TRUE
J 2
(-4475 3850);
DISPLAY 1.085106 (-4475 3850);
PAINT GREEN (-4475 3850);
DISPLAY INVISIBLE (-4475 3850);
FORCEPROP 1 LAST PATH I62
J 2
(-4148 3975);
DISPLAY 0.872340 (-4148 3975);
PAINT GREEN (-4148 3975);
DISPLAY INVISIBLE (-4148 3975);
FORCEADD TAP..1
R 2
(-4150 3775);
FORCEPROP 3 LASTPIN (-4100 3775) SIG_NAME DMI_CPU0_PCH_RX_DP<2>
J 0
(-4090 3785);
DISPLAY 0.659574 (-4090 3785);
PAINT MONO (-4090 3785);
DISPLAY INVISIBLE (-4090 3785);
FORCEPROP 1 LASTPIN (-4100 3775) BN 2
J 2
(-4088 3783);
DISPLAY 0.617021 (-4088 3783);
PAINT VIOLET (-4088 3783);
FORCEPROP 2 LAST BOM_COST SB
J 0
(-4175 3825);
DISPLAY 0.744681 (-4175 3825);
PAINT MONO (-4175 3825);
DISPLAY INVISIBLE (-4175 3825);
FORCEPROP 2 LAST CDS_LIB mstr_standard
J 0
(-4150 3775);
PAINT ORANGE (-4150 3775);
DISPLAY INVISIBLE (-4150 3775);
FORCEPROP 1 LAST BODY_TYPE PLUMBING
J 2
(-4150 3825);
DISPLAY 1.085106 (-4150 3825);
PAINT GREEN (-4150 3825);
DISPLAY INVISIBLE (-4150 3825);
FORCEPROP 1 LAST HDL_TAP TRUE
J 2
(-4475 3650);
DISPLAY 1.085106 (-4475 3650);
PAINT GREEN (-4475 3650);
DISPLAY INVISIBLE (-4475 3650);
FORCEPROP 1 LAST PATH I63
J 2
(-4148 3775);
DISPLAY 0.872340 (-4148 3775);
PAINT GREEN (-4148 3775);
DISPLAY INVISIBLE (-4148 3775);
FORCEADD TAP..1
R 2
(-4150 3375);
FORCEPROP 3 LASTPIN (-4100 3375) SIG_NAME DMI_CPU0_PCH_RX_DP<0>
J 0
(-4090 3385);
DISPLAY 0.659574 (-4090 3385);
PAINT MONO (-4090 3385);
DISPLAY INVISIBLE (-4090 3385);
FORCEPROP 1 LASTPIN (-4100 3375) BN 0
J 2
(-4088 3383);
DISPLAY 0.617021 (-4088 3383);
PAINT VIOLET (-4088 3383);
FORCEPROP 2 LAST BOM_COST SB
J 0
(-4175 3425);
DISPLAY 0.744681 (-4175 3425);
PAINT MONO (-4175 3425);
DISPLAY INVISIBLE (-4175 3425);
FORCEPROP 2 LAST CDS_LIB mstr_standard
J 0
(-4150 3375);
PAINT ORANGE (-4150 3375);
DISPLAY INVISIBLE (-4150 3375);
FORCEPROP 1 LAST BODY_TYPE PLUMBING
J 2
(-4150 3425);
DISPLAY 1.085106 (-4150 3425);
PAINT GREEN (-4150 3425);
DISPLAY INVISIBLE (-4150 3425);
FORCEPROP 1 LAST HDL_TAP TRUE
J 2
(-4475 3250);
DISPLAY 1.085106 (-4475 3250);
PAINT GREEN (-4475 3250);
DISPLAY INVISIBLE (-4475 3250);
FORCEPROP 1 LAST PATH I64
J 2
(-4148 3375);
DISPLAY 0.872340 (-4148 3375);
PAINT GREEN (-4148 3375);
DISPLAY INVISIBLE (-4148 3375);
FORCEADD TAP..1
R 2
(-4150 3575);
FORCEPROP 3 LASTPIN (-4100 3575) SIG_NAME DMI_CPU0_PCH_RX_DP<1>
J 0
(-4090 3585);
DISPLAY 0.659574 (-4090 3585);
PAINT MONO (-4090 3585);
DISPLAY INVISIBLE (-4090 3585);
FORCEPROP 1 LASTPIN (-4100 3575) BN 1
J 2
(-4088 3583);
DISPLAY 0.617021 (-4088 3583);
PAINT VIOLET (-4088 3583);
FORCEPROP 2 LAST BOM_COST SB
J 0
(-4175 3625);
DISPLAY 0.744681 (-4175 3625);
PAINT MONO (-4175 3625);
DISPLAY INVISIBLE (-4175 3625);
FORCEPROP 2 LAST CDS_LIB mstr_standard
J 0
(-4150 3575);
PAINT ORANGE (-4150 3575);
DISPLAY INVISIBLE (-4150 3575);
FORCEPROP 1 LAST BODY_TYPE PLUMBING
J 2
(-4150 3625);
DISPLAY 1.085106 (-4150 3625);
PAINT GREEN (-4150 3625);
DISPLAY INVISIBLE (-4150 3625);
FORCEPROP 1 LAST HDL_TAP TRUE
J 2
(-4475 3450);
DISPLAY 1.085106 (-4475 3450);
PAINT GREEN (-4475 3450);
DISPLAY INVISIBLE (-4475 3450);
FORCEPROP 1 LAST PATH I65
J 2
(-4148 3575);
DISPLAY 0.872340 (-4148 3575);
PAINT GREEN (-4148 3575);
DISPLAY INVISIBLE (-4148 3575);
FORCEADD OFFPAGE..1
(-5050 4075);
FORCEPROP 2 LAST $XR0 117 
J 0
(-5302 4075);
DISPLAY 0.638298 (-5302 4075);
PAINT MONO (-5302 4075);
FORCEPROP 2 LAST BOM_COST SB
J 0
(-5300 4125);
DISPLAY 0.744681 (-5300 4125);
PAINT MONO (-5300 4125);
DISPLAY INVISIBLE (-5300 4125);
FORCEPROP 2 LAST CDS_LIB mstr_standard
J 0
(-5050 4075);
PAINT ORANGE (-5050 4075);
DISPLAY INVISIBLE (-5050 4075);
FORCEPROP 1 LAST OFFPAGE TRUE
J 0
(-4725 3950);
DISPLAY 1.085106 (-4725 3950);
PAINT GREEN (-4725 3950);
DISPLAY INVISIBLE (-4725 3950);
FORCEPROP 1 LAST COMMENT_BODY TRUE
J 0
(-4925 3975);
DISPLAY 1.085106 (-4925 3975);
PAINT PEACH (-4925 3975);
DISPLAY INVISIBLE (-4925 3975);
FORCEPROP 2 LAST PATH I67
J 0
(-5300 4150);
DISPLAY 1.021277 (-5300 4150);
PAINT ORANGE (-5300 4150);
DISPLAY INVISIBLE (-5300 4150);
FORCEADD CAP..1
R 1
(-3300 4725);
FORCEPROP 1 LAST LOCATION C7B27
J 0
(-3375 4825);
DISPLAY 0.617021 (-3375 4825);
PAINT AQUA (-3375 4825);
FORCEPROP 1 LAST PART_NUMBER A36096-155
J 0
(-3450 4775);
DISPLAY 0.617021 (-3450 4775);
PAINT BLUE (-3450 4775);
FORCEPROP 1 LAST VALUE 0.22UF
J 0
(-3500 4675);
DISPLAY 0.617021 (-3500 4675);
PAINT SKYBLUE (-3500 4675);
FORCEPROP 1 LAST TOLERANCE 10%
J 0
(-3475 4625);
DISPLAY 0.617021 (-3475 4625);
PAINT SKYBLUE (-3475 4625);
FORCEPROP 1 LAST PACK_TYPE 0402
J 0
(-3475 4575);
DISPLAY 0.617021 (-3475 4575);
PAINT SKYBLUE (-3475 4575);
FORCEPROP 1 LAST MATERIAL X7R
J 0
(-3250 4625);
DISPLAY 0.617021 (-3250 4625);
PAINT SKYBLUE (-3250 4625);
FORCEPROP 1 LASTPIN (-3200 4725) $PN 2
J 0
(-3230 4735);
DISPLAY 0.617021 (-3230 4735);
PAINT WHITE (-3230 4735);
FORCEPROP 1 LASTPIN (-3400 4725) $PN 1
J 0
(-3405 4735);
DISPLAY 0.617021 (-3405 4735);
PAINT WHITE (-3405 4735);
FORCEPROP 1 LAST VOLTAGE 16V
J 0
(-3250 4675);
DISPLAY 0.510638 (-3250 4675);
PAINT SKYBLUE (-3250 4675);
DISPLAY INVISIBLE (-3250 4675);
FORCEPROP 2 LAST BOM_COST SB
J 0
(-3375 4875);
DISPLAY 0.744681 (-3375 4875);
PAINT MONO (-3375 4875);
DISPLAY INVISIBLE (-3375 4875);
FORCEPROP 2 LAST CDS_LIB mstr_discrete
J 0
(-3300 4725);
PAINT ORANGE (-3300 4725);
DISPLAY INVISIBLE (-3300 4725);
FORCEPROP 2 LAST CDS_SEC 1
J 0
(-3175 5025);
PAINT MONO (-3175 5025);
DISPLAY INVISIBLE (-3175 5025);
FORCEPROP 2 LAST $SEC 1
J 0
(-3175 5025);
PAINT MONO (-3175 5025);
DISPLAY INVISIBLE (-3175 5025);
FORCEPROP 2 LAST CDS_LOCATION C7B27
J 0
(-3375 4825);
DISPLAY 0.617021 (-3375 4825);
PAINT AQUA (-3375 4825);
DISPLAY INVISIBLE (-3375 4825);
FORCEPROP 1 LAST PATH I69
R 1
J 0
(-3450 4775);
DISPLAY 0.978723 (-3450 4775);
PAINT WHITE (-3450 4775);
DISPLAY INVISIBLE (-3450 4775);
FORCEPROP 2 LAST ROOM DMI
J 0
(-3175 5025);
PAINT ORANGE (-3175 5025);
DISPLAY INVISIBLE (-3175 5025);
FORCEADD CAP..1
R 1
(-3650 4525);
FORCEPROP 1 LAST LOCATION C7B28
J 0
(-3725 4625);
DISPLAY 0.617021 (-3725 4625);
PAINT AQUA (-3725 4625);
FORCEPROP 1 LAST PART_NUMBER A36096-155
J 0
(-3800 4575);
DISPLAY 0.617021 (-3800 4575);
PAINT BLUE (-3800 4575);
FORCEPROP 1 LAST VALUE 0.22UF
J 0
(-3850 4475);
DISPLAY 0.617021 (-3850 4475);
PAINT SKYBLUE (-3850 4475);
FORCEPROP 1 LAST TOLERANCE 10%
J 0
(-3825 4425);
DISPLAY 0.617021 (-3825 4425);
PAINT SKYBLUE (-3825 4425);
FORCEPROP 1 LAST PACK_TYPE 0402
J 0
(-3825 4375);
DISPLAY 0.617021 (-3825 4375);
PAINT SKYBLUE (-3825 4375);
FORCEPROP 1 LAST MATERIAL X7R
J 0
(-3600 4425);
DISPLAY 0.617021 (-3600 4425);
PAINT SKYBLUE (-3600 4425);
FORCEPROP 1 LASTPIN (-3550 4525) $PN 2
J 0
(-3580 4535);
DISPLAY 0.617021 (-3580 4535);
PAINT WHITE (-3580 4535);
FORCEPROP 1 LASTPIN (-3750 4525) $PN 1
J 0
(-3755 4535);
DISPLAY 0.617021 (-3755 4535);
PAINT WHITE (-3755 4535);
FORCEPROP 1 LAST VOLTAGE 16V
J 0
(-3600 4475);
DISPLAY 0.510638 (-3600 4475);
PAINT SKYBLUE (-3600 4475);
DISPLAY INVISIBLE (-3600 4475);
FORCEPROP 2 LAST BOM_COST SB
J 0
(-3725 4675);
DISPLAY 0.744681 (-3725 4675);
PAINT MONO (-3725 4675);
DISPLAY INVISIBLE (-3725 4675);
FORCEPROP 2 LAST CDS_LIB mstr_discrete
J 0
(-3650 4525);
PAINT ORANGE (-3650 4525);
DISPLAY INVISIBLE (-3650 4525);
FORCEPROP 2 LAST CDS_SEC 1
J 0
(-3525 4825);
PAINT MONO (-3525 4825);
DISPLAY INVISIBLE (-3525 4825);
FORCEPROP 2 LAST $SEC 1
J 0
(-3525 4825);
PAINT MONO (-3525 4825);
DISPLAY INVISIBLE (-3525 4825);
FORCEPROP 2 LAST CDS_LOCATION C7B28
J 0
(-3725 4625);
DISPLAY 0.617021 (-3725 4625);
PAINT AQUA (-3725 4625);
DISPLAY INVISIBLE (-3725 4625);
FORCEPROP 1 LAST PATH I70
R 1
J 0
(-3800 4575);
DISPLAY 0.978723 (-3800 4575);
PAINT WHITE (-3800 4575);
DISPLAY INVISIBLE (-3800 4575);
FORCEPROP 2 LAST ROOM DMI
J 0
(-3525 4825);
PAINT ORANGE (-3525 4825);
DISPLAY INVISIBLE (-3525 4825);
FORCEADD CAP..1
R 1
(-3300 4325);
FORCEPROP 1 LAST LOCATION C7C2
J 0
(-3375 4425);
DISPLAY 0.617021 (-3375 4425);
PAINT AQUA (-3375 4425);
FORCEPROP 1 LAST PART_NUMBER A36096-155
J 0
(-3450 4375);
DISPLAY 0.617021 (-3450 4375);
PAINT BLUE (-3450 4375);
FORCEPROP 1 LAST VALUE 0.22UF
J 0
(-3500 4275);
DISPLAY 0.617021 (-3500 4275);
PAINT SKYBLUE (-3500 4275);
FORCEPROP 1 LAST TOLERANCE 10%
J 0
(-3475 4225);
DISPLAY 0.617021 (-3475 4225);
PAINT SKYBLUE (-3475 4225);
FORCEPROP 1 LAST PACK_TYPE 0402
J 0
(-3475 4175);
DISPLAY 0.617021 (-3475 4175);
PAINT SKYBLUE (-3475 4175);
FORCEPROP 1 LAST MATERIAL X7R
J 0
(-3250 4225);
DISPLAY 0.617021 (-3250 4225);
PAINT SKYBLUE (-3250 4225);
FORCEPROP 1 LASTPIN (-3200 4325) $PN 2
J 0
(-3230 4335);
DISPLAY 0.617021 (-3230 4335);
PAINT WHITE (-3230 4335);
FORCEPROP 1 LASTPIN (-3400 4325) $PN 1
J 0
(-3405 4335);
DISPLAY 0.617021 (-3405 4335);
PAINT WHITE (-3405 4335);
FORCEPROP 1 LAST VOLTAGE 16V
J 0
(-3250 4275);
DISPLAY 0.510638 (-3250 4275);
PAINT SKYBLUE (-3250 4275);
DISPLAY INVISIBLE (-3250 4275);
FORCEPROP 2 LAST BOM_COST SB
J 0
(-3375 4475);
DISPLAY 0.744681 (-3375 4475);
PAINT MONO (-3375 4475);
DISPLAY INVISIBLE (-3375 4475);
FORCEPROP 2 LAST CDS_LIB mstr_discrete
J 0
(-3300 4325);
PAINT ORANGE (-3300 4325);
DISPLAY INVISIBLE (-3300 4325);
FORCEPROP 2 LAST CDS_SEC 1
J 0
(-3175 4625);
PAINT MONO (-3175 4625);
DISPLAY INVISIBLE (-3175 4625);
FORCEPROP 2 LAST $SEC 1
J 0
(-3175 4625);
PAINT MONO (-3175 4625);
DISPLAY INVISIBLE (-3175 4625);
FORCEPROP 2 LAST CDS_LOCATION C7C2
J 0
(-3375 4425);
DISPLAY 0.617021 (-3375 4425);
PAINT AQUA (-3375 4425);
DISPLAY INVISIBLE (-3375 4425);
FORCEPROP 1 LAST PATH I71
R 1
J 0
(-3450 4375);
DISPLAY 0.978723 (-3450 4375);
PAINT WHITE (-3450 4375);
DISPLAY INVISIBLE (-3450 4375);
FORCEPROP 2 LAST ROOM DMI
J 0
(-3175 4625);
PAINT ORANGE (-3175 4625);
DISPLAY INVISIBLE (-3175 4625);
FORCEADD CAP..1
R 1
(-3300 3375);
FORCEPROP 1 LAST LOCATION C3M40
J 0
(-3375 3475);
DISPLAY 0.617021 (-3375 3475);
PAINT AQUA (-3375 3475);
FORCEPROP 1 LAST PART_NUMBER A36096-155
J 0
(-3450 3425);
DISPLAY 0.617021 (-3450 3425);
PAINT BLUE (-3450 3425);
FORCEPROP 1 LAST VALUE 0.22UF
J 0
(-3500 3325);
DISPLAY 0.617021 (-3500 3325);
PAINT SKYBLUE (-3500 3325);
FORCEPROP 1 LAST TOLERANCE 10%
J 0
(-3475 3275);
DISPLAY 0.617021 (-3475 3275);
PAINT SKYBLUE (-3475 3275);
FORCEPROP 1 LAST MATERIAL X7R
J 0
(-3250 3275);
DISPLAY 0.617021 (-3250 3275);
PAINT SKYBLUE (-3250 3275);
FORCEPROP 1 LASTPIN (-3200 3375) $PN 2
J 0
(-3230 3385);
DISPLAY 0.617021 (-3230 3385);
PAINT WHITE (-3230 3385);
FORCEPROP 1 LASTPIN (-3400 3375) $PN 1
J 0
(-3405 3385);
DISPLAY 0.617021 (-3405 3385);
PAINT WHITE (-3405 3385);
FORCEPROP 1 LAST PACK_TYPE 0402
J 0
(-3475 3225);
DISPLAY 0.617021 (-3475 3225);
PAINT SKYBLUE (-3475 3225);
FORCEPROP 1 LAST VOLTAGE 16V
J 0
(-3250 3325);
DISPLAY 0.510638 (-3250 3325);
PAINT SKYBLUE (-3250 3325);
DISPLAY INVISIBLE (-3250 3325);
FORCEPROP 2 LAST CDS_LIB mstr_discrete
J 0
(-3300 3375);
PAINT ORANGE (-3300 3375);
DISPLAY INVISIBLE (-3300 3375);
FORCEPROP 2 LAST BOM_COST SB
J 0
(-3375 3525);
DISPLAY 0.744681 (-3375 3525);
PAINT MONO (-3375 3525);
DISPLAY INVISIBLE (-3375 3525);
FORCEPROP 2 LAST CDS_SEC 1
J 0
(-3175 3675);
PAINT MONO (-3175 3675);
DISPLAY INVISIBLE (-3175 3675);
FORCEPROP 2 LAST $SEC 1
J 0
(-3175 3675);
PAINT MONO (-3175 3675);
DISPLAY INVISIBLE (-3175 3675);
FORCEPROP 2 LAST CDS_LOCATION C3M40
J 0
(-3375 3475);
DISPLAY 0.617021 (-3375 3475);
PAINT AQUA (-3375 3475);
DISPLAY INVISIBLE (-3375 3475);
FORCEPROP 1 LAST PATH I72
R 1
J 0
(-3450 3425);
DISPLAY 0.978723 (-3450 3425);
PAINT WHITE (-3450 3425);
DISPLAY INVISIBLE (-3450 3425);
FORCEPROP 2 LAST ROOM DMI
J 0
(-3175 3675);
PAINT ORANGE (-3175 3675);
DISPLAY INVISIBLE (-3175 3675);
FORCEADD CAP..1
R 1
(-3650 3575);
FORCEPROP 1 LAST LOCATION C3M37
J 0
(-3725 3675);
DISPLAY 0.617021 (-3725 3675);
PAINT AQUA (-3725 3675);
FORCEPROP 1 LAST PART_NUMBER A36096-155
J 0
(-3800 3625);
DISPLAY 0.617021 (-3800 3625);
PAINT BLUE (-3800 3625);
FORCEPROP 1 LAST VALUE 0.22UF
J 0
(-3850 3525);
DISPLAY 0.617021 (-3850 3525);
PAINT SKYBLUE (-3850 3525);
FORCEPROP 1 LAST TOLERANCE 10%
J 0
(-3825 3475);
DISPLAY 0.617021 (-3825 3475);
PAINT SKYBLUE (-3825 3475);
FORCEPROP 1 LAST PACK_TYPE 0402
J 0
(-3825 3425);
DISPLAY 0.617021 (-3825 3425);
PAINT SKYBLUE (-3825 3425);
FORCEPROP 1 LAST MATERIAL X7R
J 0
(-3600 3475);
DISPLAY 0.617021 (-3600 3475);
PAINT SKYBLUE (-3600 3475);
FORCEPROP 1 LASTPIN (-3550 3575) $PN 2
J 0
(-3580 3585);
DISPLAY 0.617021 (-3580 3585);
PAINT WHITE (-3580 3585);
FORCEPROP 1 LASTPIN (-3750 3575) $PN 1
J 0
(-3755 3585);
DISPLAY 0.617021 (-3755 3585);
PAINT WHITE (-3755 3585);
FORCEPROP 1 LAST VOLTAGE 16V
J 0
(-3600 3525);
DISPLAY 0.510638 (-3600 3525);
PAINT SKYBLUE (-3600 3525);
DISPLAY INVISIBLE (-3600 3525);
FORCEPROP 2 LAST CDS_LIB mstr_discrete
J 0
(-3650 3575);
PAINT ORANGE (-3650 3575);
DISPLAY INVISIBLE (-3650 3575);
FORCEPROP 2 LAST BOM_COST SB
J 0
(-3725 3725);
DISPLAY 0.744681 (-3725 3725);
PAINT MONO (-3725 3725);
DISPLAY INVISIBLE (-3725 3725);
FORCEPROP 2 LAST CDS_SEC 1
J 0
(-3525 3875);
PAINT MONO (-3525 3875);
DISPLAY INVISIBLE (-3525 3875);
FORCEPROP 2 LAST $SEC 1
J 0
(-3525 3875);
PAINT MONO (-3525 3875);
DISPLAY INVISIBLE (-3525 3875);
FORCEPROP 2 LAST CDS_LOCATION C3M37
J 0
(-3725 3675);
DISPLAY 0.617021 (-3725 3675);
PAINT AQUA (-3725 3675);
DISPLAY INVISIBLE (-3725 3675);
FORCEPROP 1 LAST PATH I73
R 1
J 0
(-3800 3625);
DISPLAY 0.978723 (-3800 3625);
PAINT WHITE (-3800 3625);
DISPLAY INVISIBLE (-3800 3625);
FORCEPROP 2 LAST ROOM DMI
J 0
(-3525 3875);
PAINT ORANGE (-3525 3875);
DISPLAY INVISIBLE (-3525 3875);
FORCEADD CAP..1
R 1
(-3300 3775);
FORCEPROP 1 LAST LOCATION C3N9
J 0
(-3375 3875);
DISPLAY 0.617021 (-3375 3875);
PAINT AQUA (-3375 3875);
FORCEPROP 1 LAST PART_NUMBER A36096-155
J 0
(-3450 3825);
DISPLAY 0.617021 (-3450 3825);
PAINT BLUE (-3450 3825);
FORCEPROP 1 LAST VALUE 0.22UF
J 0
(-3500 3725);
DISPLAY 0.617021 (-3500 3725);
PAINT SKYBLUE (-3500 3725);
FORCEPROP 1 LAST TOLERANCE 10%
J 0
(-3475 3675);
DISPLAY 0.617021 (-3475 3675);
PAINT SKYBLUE (-3475 3675);
FORCEPROP 1 LAST PACK_TYPE 0402
J 0
(-3475 3625);
DISPLAY 0.617021 (-3475 3625);
PAINT SKYBLUE (-3475 3625);
FORCEPROP 1 LAST MATERIAL X7R
J 0
(-3250 3675);
DISPLAY 0.617021 (-3250 3675);
PAINT SKYBLUE (-3250 3675);
FORCEPROP 1 LASTPIN (-3200 3775) $PN 2
J 0
(-3230 3785);
DISPLAY 0.617021 (-3230 3785);
PAINT WHITE (-3230 3785);
FORCEPROP 1 LASTPIN (-3400 3775) $PN 1
J 0
(-3405 3785);
DISPLAY 0.617021 (-3405 3785);
PAINT WHITE (-3405 3785);
FORCEPROP 1 LAST VOLTAGE 16V
J 0
(-3250 3725);
DISPLAY 0.510638 (-3250 3725);
PAINT SKYBLUE (-3250 3725);
DISPLAY INVISIBLE (-3250 3725);
FORCEPROP 2 LAST CDS_LIB mstr_discrete
J 0
(-3300 3775);
PAINT ORANGE (-3300 3775);
DISPLAY INVISIBLE (-3300 3775);
FORCEPROP 2 LAST BOM_COST SB
J 0
(-3375 3925);
DISPLAY 0.744681 (-3375 3925);
PAINT MONO (-3375 3925);
DISPLAY INVISIBLE (-3375 3925);
FORCEPROP 2 LAST CDS_SEC 1
J 0
(-3175 4075);
PAINT MONO (-3175 4075);
DISPLAY INVISIBLE (-3175 4075);
FORCEPROP 2 LAST $SEC 1
J 0
(-3175 4075);
PAINT MONO (-3175 4075);
DISPLAY INVISIBLE (-3175 4075);
FORCEPROP 2 LAST CDS_LOCATION C3N9
J 0
(-3375 3875);
DISPLAY 0.617021 (-3375 3875);
PAINT AQUA (-3375 3875);
DISPLAY INVISIBLE (-3375 3875);
FORCEPROP 1 LAST PATH I74
R 1
J 0
(-3450 3825);
DISPLAY 0.978723 (-3450 3825);
PAINT WHITE (-3450 3825);
DISPLAY INVISIBLE (-3450 3825);
FORCEPROP 2 LAST ROOM DMI
J 0
(-3175 4075);
PAINT ORANGE (-3175 4075);
DISPLAY INVISIBLE (-3175 4075);
FORCEADD CAP..1
R 1
(-3650 3975);
FORCEPROP 1 LAST LOCATION C3N8
J 0
(-3725 4075);
DISPLAY 0.617021 (-3725 4075);
PAINT AQUA (-3725 4075);
FORCEPROP 1 LAST PART_NUMBER A36096-155
J 0
(-3800 4025);
DISPLAY 0.617021 (-3800 4025);
PAINT BLUE (-3800 4025);
FORCEPROP 1 LAST VALUE 0.22UF
J 0
(-3850 3925);
DISPLAY 0.617021 (-3850 3925);
PAINT SKYBLUE (-3850 3925);
FORCEPROP 1 LAST TOLERANCE 10%
J 0
(-3825 3875);
DISPLAY 0.617021 (-3825 3875);
PAINT SKYBLUE (-3825 3875);
FORCEPROP 1 LAST PACK_TYPE 0402
J 0
(-3825 3825);
DISPLAY 0.617021 (-3825 3825);
PAINT SKYBLUE (-3825 3825);
FORCEPROP 1 LAST MATERIAL X7R
J 0
(-3600 3875);
DISPLAY 0.617021 (-3600 3875);
PAINT SKYBLUE (-3600 3875);
FORCEPROP 1 LASTPIN (-3550 3975) $PN 2
J 0
(-3580 3985);
DISPLAY 0.617021 (-3580 3985);
PAINT WHITE (-3580 3985);
FORCEPROP 1 LASTPIN (-3750 3975) $PN 1
J 0
(-3755 3985);
DISPLAY 0.617021 (-3755 3985);
PAINT WHITE (-3755 3985);
FORCEPROP 1 LAST VOLTAGE 16V
J 0
(-3600 3925);
DISPLAY 0.510638 (-3600 3925);
PAINT SKYBLUE (-3600 3925);
DISPLAY INVISIBLE (-3600 3925);
FORCEPROP 2 LAST CDS_LIB mstr_discrete
J 0
(-3650 3975);
PAINT ORANGE (-3650 3975);
DISPLAY INVISIBLE (-3650 3975);
FORCEPROP 2 LAST BOM_COST SB
J 0
(-3725 4125);
DISPLAY 0.744681 (-3725 4125);
PAINT MONO (-3725 4125);
DISPLAY INVISIBLE (-3725 4125);
FORCEPROP 2 LAST CDS_SEC 1
J 0
(-3525 4275);
PAINT MONO (-3525 4275);
DISPLAY INVISIBLE (-3525 4275);
FORCEPROP 2 LAST $SEC 1
J 0
(-3525 4275);
PAINT MONO (-3525 4275);
DISPLAY INVISIBLE (-3525 4275);
FORCEPROP 2 LAST CDS_LOCATION C3N8
J 0
(-3725 4075);
DISPLAY 0.617021 (-3725 4075);
PAINT AQUA (-3725 4075);
DISPLAY INVISIBLE (-3725 4075);
FORCEPROP 1 LAST PATH I75
R 1
J 0
(-3800 4025);
DISPLAY 0.978723 (-3800 4025);
PAINT WHITE (-3800 4025);
DISPLAY INVISIBLE (-3800 4025);
FORCEPROP 2 LAST ROOM DMI
J 0
(-3525 4275);
PAINT ORANGE (-3525 4275);
DISPLAY INVISIBLE (-3525 4275);
FORCEADD CAP..1
R 1
(750 4325);
FORCEPROP 1 LAST LOCATION C7C3
J 0
(675 4425);
DISPLAY 0.617021 (675 4425);
PAINT AQUA (675 4425);
FORCEPROP 1 LAST PART_NUMBER A36096-155
J 0
(600 4375);
DISPLAY 0.617021 (600 4375);
PAINT BLUE (600 4375);
FORCEPROP 1 LAST VALUE 0.22UF
J 0
(550 4275);
DISPLAY 0.617021 (550 4275);
PAINT SKYBLUE (550 4275);
FORCEPROP 1 LAST TOLERANCE 10%
J 0
(575 4225);
DISPLAY 0.617021 (575 4225);
PAINT SKYBLUE (575 4225);
FORCEPROP 1 LAST PACK_TYPE 0402
J 0
(575 4175);
DISPLAY 0.617021 (575 4175);
PAINT SKYBLUE (575 4175);
FORCEPROP 1 LAST MATERIAL X7R
J 0
(800 4225);
DISPLAY 0.617021 (800 4225);
PAINT SKYBLUE (800 4225);
FORCEPROP 1 LASTPIN (850 4325) $PN 2
J 0
(820 4335);
DISPLAY 0.617021 (820 4335);
PAINT WHITE (820 4335);
FORCEPROP 1 LASTPIN (650 4325) $PN 1
J 0
(645 4335);
DISPLAY 0.617021 (645 4335);
PAINT WHITE (645 4335);
FORCEPROP 1 LAST VOLTAGE 16V
J 0
(800 4275);
DISPLAY 0.510638 (800 4275);
PAINT SKYBLUE (800 4275);
DISPLAY INVISIBLE (800 4275);
FORCEPROP 2 LAST CDS_LIB mstr_discrete
J 0
(750 4325);
PAINT ORANGE (750 4325);
DISPLAY INVISIBLE (750 4325);
FORCEPROP 2 LAST BOM_COST SB
J 0
(675 4475);
DISPLAY 0.744681 (675 4475);
PAINT MONO (675 4475);
DISPLAY INVISIBLE (675 4475);
FORCEPROP 2 LAST CDS_SEC 1
J 0
(875 4625);
PAINT MONO (875 4625);
DISPLAY INVISIBLE (875 4625);
FORCEPROP 2 LAST $SEC 1
J 0
(875 4625);
PAINT MONO (875 4625);
DISPLAY INVISIBLE (875 4625);
FORCEPROP 2 LAST CDS_LOCATION C7C3
J 0
(675 4425);
DISPLAY 0.617021 (675 4425);
PAINT AQUA (675 4425);
DISPLAY INVISIBLE (675 4425);
FORCEPROP 1 LAST PATH I76
R 1
J 0
(600 4375);
DISPLAY 0.978723 (600 4375);
PAINT WHITE (600 4375);
DISPLAY INVISIBLE (600 4375);
FORCEPROP 2 LAST ROOM DMI
J 0
(875 4625);
PAINT ORANGE (875 4625);
DISPLAY INVISIBLE (875 4625);
FORCEADD CAP..1
R 1
(400 4525);
FORCEPROP 1 LAST LOCATION C7C1
J 0
(325 4625);
DISPLAY 0.617021 (325 4625);
PAINT AQUA (325 4625);
FORCEPROP 1 LAST PART_NUMBER A36096-155
J 0
(250 4575);
DISPLAY 0.617021 (250 4575);
PAINT BLUE (250 4575);
FORCEPROP 1 LAST VALUE 0.22UF
J 0
(200 4475);
DISPLAY 0.617021 (200 4475);
PAINT SKYBLUE (200 4475);
FORCEPROP 1 LAST TOLERANCE 10%
J 0
(225 4425);
DISPLAY 0.617021 (225 4425);
PAINT SKYBLUE (225 4425);
FORCEPROP 1 LAST PACK_TYPE 0402
J 0
(225 4375);
DISPLAY 0.617021 (225 4375);
PAINT SKYBLUE (225 4375);
FORCEPROP 1 LAST MATERIAL X7R
J 0
(450 4425);
DISPLAY 0.617021 (450 4425);
PAINT SKYBLUE (450 4425);
FORCEPROP 1 LASTPIN (500 4525) $PN 2
J 0
(470 4535);
DISPLAY 0.617021 (470 4535);
PAINT WHITE (470 4535);
FORCEPROP 1 LASTPIN (300 4525) $PN 1
J 0
(295 4535);
DISPLAY 0.617021 (295 4535);
PAINT WHITE (295 4535);
FORCEPROP 1 LAST VOLTAGE 16V
J 0
(450 4475);
DISPLAY 0.510638 (450 4475);
PAINT SKYBLUE (450 4475);
DISPLAY INVISIBLE (450 4475);
FORCEPROP 2 LAST CDS_LIB mstr_discrete
J 0
(400 4525);
PAINT ORANGE (400 4525);
DISPLAY INVISIBLE (400 4525);
FORCEPROP 2 LAST BOM_COST SB
J 0
(325 4675);
DISPLAY 0.744681 (325 4675);
PAINT MONO (325 4675);
DISPLAY INVISIBLE (325 4675);
FORCEPROP 2 LAST CDS_SEC 1
J 0
(525 4825);
PAINT MONO (525 4825);
DISPLAY INVISIBLE (525 4825);
FORCEPROP 2 LAST $SEC 1
J 0
(525 4825);
PAINT MONO (525 4825);
DISPLAY INVISIBLE (525 4825);
FORCEPROP 2 LAST CDS_LOCATION C7C1
J 0
(325 4625);
DISPLAY 0.617021 (325 4625);
PAINT AQUA (325 4625);
DISPLAY INVISIBLE (325 4625);
FORCEPROP 1 LAST PATH I77
R 1
J 0
(250 4575);
DISPLAY 0.978723 (250 4575);
PAINT WHITE (250 4575);
DISPLAY INVISIBLE (250 4575);
FORCEPROP 2 LAST ROOM DMI
J 0
(525 4825);
PAINT ORANGE (525 4825);
DISPLAY INVISIBLE (525 4825);
FORCEADD CAP..1
R 1
(750 4725);
FORCEPROP 1 LAST LOCATION C7B29
J 0
(675 4825);
DISPLAY 0.617021 (675 4825);
PAINT AQUA (675 4825);
FORCEPROP 1 LAST PART_NUMBER A36096-155
J 0
(600 4775);
DISPLAY 0.617021 (600 4775);
PAINT BLUE (600 4775);
FORCEPROP 1 LAST VALUE 0.22UF
J 0
(550 4675);
DISPLAY 0.617021 (550 4675);
PAINT SKYBLUE (550 4675);
FORCEPROP 1 LAST TOLERANCE 10%
J 0
(575 4625);
DISPLAY 0.617021 (575 4625);
PAINT SKYBLUE (575 4625);
FORCEPROP 1 LAST PACK_TYPE 0402
J 0
(575 4575);
DISPLAY 0.617021 (575 4575);
PAINT SKYBLUE (575 4575);
FORCEPROP 1 LAST MATERIAL X7R
J 0
(800 4625);
DISPLAY 0.617021 (800 4625);
PAINT SKYBLUE (800 4625);
FORCEPROP 1 LASTPIN (850 4725) $PN 2
J 0
(820 4735);
DISPLAY 0.617021 (820 4735);
PAINT WHITE (820 4735);
FORCEPROP 1 LASTPIN (650 4725) $PN 1
J 0
(645 4735);
DISPLAY 0.617021 (645 4735);
PAINT WHITE (645 4735);
FORCEPROP 1 LAST VOLTAGE 16V
J 0
(800 4675);
DISPLAY 0.510638 (800 4675);
PAINT SKYBLUE (800 4675);
DISPLAY INVISIBLE (800 4675);
FORCEPROP 2 LAST CDS_LIB mstr_discrete
J 0
(750 4725);
PAINT ORANGE (750 4725);
DISPLAY INVISIBLE (750 4725);
FORCEPROP 2 LAST BOM_COST SB
J 0
(675 4875);
DISPLAY 0.744681 (675 4875);
PAINT MONO (675 4875);
DISPLAY INVISIBLE (675 4875);
FORCEPROP 2 LAST CDS_SEC 1
J 0
(875 5025);
PAINT MONO (875 5025);
DISPLAY INVISIBLE (875 5025);
FORCEPROP 2 LAST $SEC 1
J 0
(875 5025);
PAINT MONO (875 5025);
DISPLAY INVISIBLE (875 5025);
FORCEPROP 2 LAST CDS_LOCATION C7B29
J 0
(675 4825);
DISPLAY 0.617021 (675 4825);
PAINT AQUA (675 4825);
DISPLAY INVISIBLE (675 4825);
FORCEPROP 1 LAST PATH I78
R 1
J 0
(600 4775);
DISPLAY 0.978723 (600 4775);
PAINT WHITE (600 4775);
DISPLAY INVISIBLE (600 4775);
FORCEPROP 2 LAST ROOM DMI
J 0
(875 5025);
PAINT ORANGE (875 5025);
DISPLAY INVISIBLE (875 5025);
FORCEADD CAP..1
R 1
(400 4925);
FORCEPROP 1 LAST LOCATION C7B26
J 0
(325 5025);
DISPLAY 0.617021 (325 5025);
PAINT AQUA (325 5025);
FORCEPROP 1 LAST PART_NUMBER A36096-155
J 0
(250 4975);
DISPLAY 0.617021 (250 4975);
PAINT BLUE (250 4975);
FORCEPROP 1 LAST VALUE 0.22UF
J 0
(200 4875);
DISPLAY 0.617021 (200 4875);
PAINT SKYBLUE (200 4875);
FORCEPROP 1 LAST TOLERANCE 10%
J 0
(225 4825);
DISPLAY 0.617021 (225 4825);
PAINT SKYBLUE (225 4825);
FORCEPROP 1 LAST PACK_TYPE 0402
J 0
(225 4775);
DISPLAY 0.617021 (225 4775);
PAINT SKYBLUE (225 4775);
FORCEPROP 1 LAST MATERIAL X7R
J 0
(450 4825);
DISPLAY 0.617021 (450 4825);
PAINT SKYBLUE (450 4825);
FORCEPROP 1 LASTPIN (500 4925) $PN 2
J 0
(470 4935);
DISPLAY 0.617021 (470 4935);
PAINT WHITE (470 4935);
FORCEPROP 1 LASTPIN (300 4925) $PN 1
J 0
(295 4935);
DISPLAY 0.617021 (295 4935);
PAINT WHITE (295 4935);
FORCEPROP 1 LAST VOLTAGE 16V
J 0
(450 4875);
DISPLAY 0.510638 (450 4875);
PAINT SKYBLUE (450 4875);
DISPLAY INVISIBLE (450 4875);
FORCEPROP 2 LAST CDS_LIB mstr_discrete
J 0
(400 4925);
PAINT ORANGE (400 4925);
DISPLAY INVISIBLE (400 4925);
FORCEPROP 2 LAST BOM_COST SB
J 0
(325 5075);
DISPLAY 0.744681 (325 5075);
PAINT MONO (325 5075);
DISPLAY INVISIBLE (325 5075);
FORCEPROP 2 LAST CDS_SEC 1
J 0
(525 5225);
PAINT MONO (525 5225);
DISPLAY INVISIBLE (525 5225);
FORCEPROP 2 LAST $SEC 1
J 0
(525 5225);
PAINT MONO (525 5225);
DISPLAY INVISIBLE (525 5225);
FORCEPROP 2 LAST CDS_LOCATION C7B26
J 0
(325 5025);
DISPLAY 0.617021 (325 5025);
PAINT AQUA (325 5025);
DISPLAY INVISIBLE (325 5025);
FORCEPROP 1 LAST PATH I79
R 1
J 0
(250 4975);
DISPLAY 0.978723 (250 4975);
PAINT WHITE (250 4975);
DISPLAY INVISIBLE (250 4975);
FORCEPROP 2 LAST ROOM DMI
J 0
(525 5225);
PAINT ORANGE (525 5225);
DISPLAY INVISIBLE (525 5225);
FORCEADD CAP..1
R 1
(750 3375);
FORCEPROP 1 LAST LOCATION C3M44
J 0
(675 3475);
DISPLAY 0.617021 (675 3475);
PAINT AQUA (675 3475);
FORCEPROP 1 LAST PART_NUMBER A36096-155
J 0
(600 3425);
DISPLAY 0.617021 (600 3425);
PAINT BLUE (600 3425);
FORCEPROP 1 LAST VALUE 0.22UF
J 0
(550 3325);
DISPLAY 0.617021 (550 3325);
PAINT SKYBLUE (550 3325);
FORCEPROP 1 LAST TOLERANCE 10%
J 0
(575 3275);
DISPLAY 0.617021 (575 3275);
PAINT SKYBLUE (575 3275);
FORCEPROP 1 LAST PACK_TYPE 0402
J 0
(575 3225);
DISPLAY 0.617021 (575 3225);
PAINT SKYBLUE (575 3225);
FORCEPROP 1 LAST MATERIAL X7R
J 0
(800 3275);
DISPLAY 0.617021 (800 3275);
PAINT SKYBLUE (800 3275);
FORCEPROP 1 LASTPIN (850 3375) $PN 2
J 0
(820 3385);
DISPLAY 0.617021 (820 3385);
PAINT WHITE (820 3385);
FORCEPROP 1 LASTPIN (650 3375) $PN 1
J 0
(645 3385);
DISPLAY 0.617021 (645 3385);
PAINT WHITE (645 3385);
FORCEPROP 1 LAST VOLTAGE 16V
J 0
(800 3325);
DISPLAY 0.510638 (800 3325);
PAINT SKYBLUE (800 3325);
DISPLAY INVISIBLE (800 3325);
FORCEPROP 2 LAST CDS_LIB mstr_discrete
J 0
(750 3375);
PAINT ORANGE (750 3375);
DISPLAY INVISIBLE (750 3375);
FORCEPROP 2 LAST BOM_COST SB
J 0
(675 3525);
DISPLAY 0.744681 (675 3525);
PAINT MONO (675 3525);
DISPLAY INVISIBLE (675 3525);
FORCEPROP 2 LAST CDS_SEC 1
J 0
(875 3675);
PAINT MONO (875 3675);
DISPLAY INVISIBLE (875 3675);
FORCEPROP 2 LAST $SEC 1
J 0
(875 3675);
PAINT MONO (875 3675);
DISPLAY INVISIBLE (875 3675);
FORCEPROP 2 LAST CDS_LOCATION C3M44
J 0
(675 3475);
DISPLAY 0.617021 (675 3475);
PAINT AQUA (675 3475);
DISPLAY INVISIBLE (675 3475);
FORCEPROP 1 LAST PATH I80
R 1
J 0
(600 3425);
DISPLAY 0.978723 (600 3425);
PAINT WHITE (600 3425);
DISPLAY INVISIBLE (600 3425);
FORCEPROP 2 LAST ROOM DMI
J 0
(875 3675);
PAINT ORANGE (875 3675);
DISPLAY INVISIBLE (875 3675);
FORCEADD CAP..1
R 1
(400 3575);
FORCEPROP 1 LAST LOCATION C3M41
J 0
(325 3675);
DISPLAY 0.617021 (325 3675);
PAINT AQUA (325 3675);
FORCEPROP 1 LAST PART_NUMBER A36096-155
J 0
(250 3625);
DISPLAY 0.617021 (250 3625);
PAINT BLUE (250 3625);
FORCEPROP 1 LAST VALUE 0.22UF
J 0
(200 3525);
DISPLAY 0.617021 (200 3525);
PAINT SKYBLUE (200 3525);
FORCEPROP 1 LAST TOLERANCE 10%
J 0
(225 3475);
DISPLAY 0.617021 (225 3475);
PAINT SKYBLUE (225 3475);
FORCEPROP 1 LAST PACK_TYPE 0402
J 0
(225 3425);
DISPLAY 0.617021 (225 3425);
PAINT SKYBLUE (225 3425);
FORCEPROP 1 LAST MATERIAL X7R
J 0
(450 3475);
DISPLAY 0.617021 (450 3475);
PAINT SKYBLUE (450 3475);
FORCEPROP 1 LASTPIN (500 3575) $PN 2
J 0
(470 3585);
DISPLAY 0.617021 (470 3585);
PAINT WHITE (470 3585);
FORCEPROP 1 LASTPIN (300 3575) $PN 1
J 0
(295 3585);
DISPLAY 0.617021 (295 3585);
PAINT WHITE (295 3585);
FORCEPROP 1 LAST VOLTAGE 16V
J 0
(450 3525);
DISPLAY 0.510638 (450 3525);
PAINT SKYBLUE (450 3525);
DISPLAY INVISIBLE (450 3525);
FORCEPROP 2 LAST CDS_LIB mstr_discrete
J 0
(400 3575);
PAINT ORANGE (400 3575);
DISPLAY INVISIBLE (400 3575);
FORCEPROP 2 LAST BOM_COST SB
J 0
(325 3725);
DISPLAY 0.744681 (325 3725);
PAINT MONO (325 3725);
DISPLAY INVISIBLE (325 3725);
FORCEPROP 2 LAST CDS_SEC 1
J 0
(525 3875);
PAINT MONO (525 3875);
DISPLAY INVISIBLE (525 3875);
FORCEPROP 2 LAST $SEC 1
J 0
(525 3875);
PAINT MONO (525 3875);
DISPLAY INVISIBLE (525 3875);
FORCEPROP 2 LAST CDS_LOCATION C3M41
J 0
(325 3675);
DISPLAY 0.617021 (325 3675);
PAINT AQUA (325 3675);
DISPLAY INVISIBLE (325 3675);
FORCEPROP 1 LAST PATH I81
R 1
J 0
(250 3625);
DISPLAY 0.978723 (250 3625);
PAINT WHITE (250 3625);
DISPLAY INVISIBLE (250 3625);
FORCEPROP 2 LAST ROOM DMI
J 0
(525 3875);
PAINT ORANGE (525 3875);
DISPLAY INVISIBLE (525 3875);
FORCEADD CAP..1
R 1
(750 3775);
FORCEPROP 1 LAST LOCATION C3M45
J 0
(675 3875);
DISPLAY 0.617021 (675 3875);
PAINT AQUA (675 3875);
FORCEPROP 1 LAST PART_NUMBER A36096-155
J 0
(600 3825);
DISPLAY 0.617021 (600 3825);
PAINT BLUE (600 3825);
FORCEPROP 1 LAST VALUE 0.22UF
J 0
(550 3725);
DISPLAY 0.617021 (550 3725);
PAINT SKYBLUE (550 3725);
FORCEPROP 1 LAST TOLERANCE 10%
J 0
(575 3675);
DISPLAY 0.617021 (575 3675);
PAINT SKYBLUE (575 3675);
FORCEPROP 1 LAST PACK_TYPE 0402
J 0
(575 3625);
DISPLAY 0.617021 (575 3625);
PAINT SKYBLUE (575 3625);
FORCEPROP 1 LAST MATERIAL X7R
J 0
(800 3675);
DISPLAY 0.617021 (800 3675);
PAINT SKYBLUE (800 3675);
FORCEPROP 1 LASTPIN (850 3775) $PN 2
J 0
(820 3785);
DISPLAY 0.617021 (820 3785);
PAINT WHITE (820 3785);
FORCEPROP 1 LASTPIN (650 3775) $PN 1
J 0
(645 3785);
DISPLAY 0.617021 (645 3785);
PAINT WHITE (645 3785);
FORCEPROP 1 LAST VOLTAGE 16V
J 0
(800 3725);
DISPLAY 0.510638 (800 3725);
PAINT SKYBLUE (800 3725);
DISPLAY INVISIBLE (800 3725);
FORCEPROP 2 LAST CDS_LIB mstr_discrete
J 0
(750 3775);
PAINT ORANGE (750 3775);
DISPLAY INVISIBLE (750 3775);
FORCEPROP 2 LAST BOM_COST SB
J 0
(675 3925);
DISPLAY 0.744681 (675 3925);
PAINT MONO (675 3925);
DISPLAY INVISIBLE (675 3925);
FORCEPROP 2 LAST CDS_SEC 1
J 0
(875 4075);
PAINT MONO (875 4075);
DISPLAY INVISIBLE (875 4075);
FORCEPROP 2 LAST $SEC 1
J 0
(875 4075);
PAINT MONO (875 4075);
DISPLAY INVISIBLE (875 4075);
FORCEPROP 2 LAST CDS_LOCATION C3M45
J 0
(675 3875);
DISPLAY 0.617021 (675 3875);
PAINT AQUA (675 3875);
DISPLAY INVISIBLE (675 3875);
FORCEPROP 1 LAST PATH I82
R 1
J 0
(600 3825);
DISPLAY 0.978723 (600 3825);
PAINT WHITE (600 3825);
DISPLAY INVISIBLE (600 3825);
FORCEPROP 2 LAST ROOM DMI
J 0
(875 4075);
PAINT ORANGE (875 4075);
DISPLAY INVISIBLE (875 4075);
FORCEADD CAP..1
R 1
(400 3975);
FORCEPROP 1 LAST LOCATION C3N13
J 0
(325 4075);
DISPLAY 0.617021 (325 4075);
PAINT AQUA (325 4075);
FORCEPROP 1 LAST PART_NUMBER A36096-155
J 0
(250 4025);
DISPLAY 0.617021 (250 4025);
PAINT BLUE (250 4025);
FORCEPROP 1 LAST VALUE 0.22UF
J 0
(200 3925);
DISPLAY 0.617021 (200 3925);
PAINT SKYBLUE (200 3925);
FORCEPROP 1 LAST TOLERANCE 10%
J 0
(225 3875);
DISPLAY 0.617021 (225 3875);
PAINT SKYBLUE (225 3875);
FORCEPROP 1 LAST PACK_TYPE 0402
J 0
(225 3825);
DISPLAY 0.617021 (225 3825);
PAINT SKYBLUE (225 3825);
FORCEPROP 1 LAST MATERIAL X7R
J 0
(450 3875);
DISPLAY 0.617021 (450 3875);
PAINT SKYBLUE (450 3875);
FORCEPROP 1 LASTPIN (500 3975) $PN 2
J 0
(470 3985);
DISPLAY 0.617021 (470 3985);
PAINT WHITE (470 3985);
FORCEPROP 1 LASTPIN (300 3975) $PN 1
J 0
(295 3985);
DISPLAY 0.617021 (295 3985);
PAINT WHITE (295 3985);
FORCEPROP 1 LAST VOLTAGE 16V
J 0
(450 3925);
DISPLAY 0.510638 (450 3925);
PAINT SKYBLUE (450 3925);
DISPLAY INVISIBLE (450 3925);
FORCEPROP 2 LAST CDS_LIB mstr_discrete
J 0
(400 3975);
PAINT ORANGE (400 3975);
DISPLAY INVISIBLE (400 3975);
FORCEPROP 2 LAST BOM_COST SB
J 0
(325 4125);
DISPLAY 0.744681 (325 4125);
PAINT MONO (325 4125);
DISPLAY INVISIBLE (325 4125);
FORCEPROP 2 LAST CDS_SEC 1
J 0
(525 4275);
PAINT MONO (525 4275);
DISPLAY INVISIBLE (525 4275);
FORCEPROP 2 LAST $SEC 1
J 0
(525 4275);
PAINT MONO (525 4275);
DISPLAY INVISIBLE (525 4275);
FORCEPROP 2 LAST CDS_LOCATION C3N13
J 0
(325 4075);
DISPLAY 0.617021 (325 4075);
PAINT AQUA (325 4075);
DISPLAY INVISIBLE (325 4075);
FORCEPROP 1 LAST PATH I83
R 1
J 0
(250 4025);
DISPLAY 0.978723 (250 4025);
PAINT WHITE (250 4025);
DISPLAY INVISIBLE (250 4025);
FORCEPROP 2 LAST ROOM DMI
J 0
(525 4275);
PAINT ORANGE (525 4275);
DISPLAY INVISIBLE (525 4275);
FORCEADD INTEL_CORP_BPAGE..1
(2650 500);
FORCEPROP 1 LAST CDS_CON_LAST_MODIFIED Tue Dec 01 11:52:00 2015
J 0
(1225 825);
PAINT ORANGE (1225 825);
DISPLAY INVISIBLE (1225 825);
FORCEPROP 1 LAST CUSTOM_TXT_CDS <CURRENT_DESIGN_SHEET> OF <TOTAL_DESIGN_SHEETS>
J 0
(2150 525);
PAINT GREEN (2150 525);
FORCEPROP 1 LAST CUSTOM_TXT_CDS <CON_LAST_MODIFIED>
J 0
(725 850);
PAINT GREEN (725 850);
FORCEPROP 2 LAST CUSTOM_TXT_CDS <XR_PAGE_TITLE>
J 0
(-5240 5750);
DISPLAY 0.638298 (-5240 5750);
PAINT PINK (-5240 5750);
DISPLAY INVISIBLE (-5240 5750);
FORCEPROP 1 LAST SCH_ADDRESS3 Santa Clara, CA 95052-8119
J 0
(-1325 525);
DISPLAY 0.617021 (-1325 525);
PAINT YELLOW (-1325 525);
FORCEPROP 1 LAST SCH_ADDRESS2 P.O. BOX 58119
J 0
(-1325 575);
DISPLAY 0.617021 (-1325 575);
PAINT YELLOW (-1325 575);
FORCEPROP 1 LAST SCH_ADDRESS1 2200 Mission College Blvd.
J 0
(-1325 625);
DISPLAY 0.617021 (-1325 625);
PAINT YELLOW (-1325 625);
FORCEPROP 1 LAST SCH_TITLE DMI AC COUPLING
J 0
(-5300 550);
DISPLAY 1.212766 (-5300 550);
PAINT YELLOW (-5300 550);
FORCEPROP 1 LAST SCH_REV 2.420
J 0
(2400 650);
DISPLAY 0.978723 (2400 650);
PAINT YELLOW (2400 650);
FORCEPROP 1 LAST SCH_DEPT BESD
J 1
(-1800 600);
DISPLAY 1.212766 (-1800 600);
PAINT YELLOW (-1800 600);
FORCEPROP 1 LAST SCH_NUMBER H4694802
J 0
(1350 650);
DISPLAY 1.212766 (1350 650);
PAINT YELLOW (1350 650);
FORCEPROP 2 LAST CDS_LIB mstr_symbols
J 0
(2650 500);
PAINT MONO (2650 500);
DISPLAY INVISIBLE (2650 500);
FORCEPROP 2 LAST PAGE_BORDER TRUE
J 0
(-5240 5750);
DISPLAY 0.851064 (-5240 5750);
PAINT PINK (-5240 5750);
DISPLAY INVISIBLE (-5240 5750);
FORCEPROP 1 LAST COMMENT_BODY TRUE
J 0
(2662 512);
DISPLAY 0.468085 (2662 512);
PAINT PEACH (2662 512);
DISPLAY INVISIBLE (2662 512);
FORCEPROP 2 LAST CDS_XR_PAGE_TITLE CR-129 : @BASEBOARD_FAB2_LIB.BASEBOARD_FAB2(SCH_1):PAGE129
J 0
(-5240 5750);
DISPLAY 0.638298 (-5240 5750);
PAINT PINK (-5240 5750);
DISPLAY INVISIBLE (-5240 5750);
WIRE 17 -1 (1250 4950)(1250 5025);
FORCEPROP 2 LAST SIG_NAME DMI_CPU0_PCH_TX_C_DN<3:0>
J 0
(1315 5060);
DISPLAY 0.617021 (1315 5060);
PAINT ORANGE (1315 5060);
WIRE 17 -1 (1250 4750)(1250 4950);
WIRE 17 -1 (1250 4550)(1250 4750);
WIRE 17 -1 (1250 4350)(1250 4550);
WIRE 17 -1 (1250 4000)(1250 4075);
FORCEPROP 2 LAST SIG_NAME DMI_CPU0_PCH_RX_C_DN<3:0>
J 0
(1340 4110);
DISPLAY 0.617021 (1340 4110);
PAINT ORANGE (1340 4110);
WIRE 17 -1 (1250 3800)(1250 4000);
WIRE 17 -1 (1250 3600)(1250 3800);
WIRE 17 -1 (1250 3400)(1250 3600);
WIRE 17 -1 (-200 3800)(-200 4000);
WIRE 17 -1 (-200 3600)(-200 3800);
WIRE 17 -1 (-200 4000)(-200 4075);
WIRE 17 -1 (-200 4075)(-950 4075);
FORCEPROP 2 LAST SIG_NAME DMI_CPU0_PCH_RX_DN<3:0>
J 0
(-935 4085);
DISPLAY 0.617021 (-935 4085);
PAINT ORANGE (-935 4085);
WIRE 17 -1 (-200 3400)(-200 3600);
WIRE 17 -1 (-175 4750)(-175 4950);
WIRE 17 -1 (-175 4550)(-175 4750);
WIRE 17 -1 (-175 4950)(-175 5025);
WIRE 17 -1 (-175 5025)(-950 5025);
FORCEPROP 2 LAST SIG_NAME DMI_CPU0_PCH_TX_DN<3:0>
J 0
(-935 5035);
DISPLAY 0.617021 (-935 5035);
PAINT ORANGE (-935 5035);
WIRE 17 -1 (-175 4350)(-175 4550);
WIRE 17 -1 (-2750 4350)(-2750 4550);
WIRE 17 -1 (-2750 4550)(-2750 4750);
WIRE 17 -1 (-2750 4750)(-2750 4950);
WIRE 17 -1 (-2750 4950)(-2750 5025);
FORCEPROP 2 LAST SIG_NAME DMI_CPU0_PCH_TX_C_DP<3:0>
J 0
(-2685 5060);
DISPLAY 0.617021 (-2685 5060);
PAINT ORANGE (-2685 5060);
WIRE 17 -1 (-2750 3600)(-2750 3800);
WIRE 17 -1 (-2750 3400)(-2750 3600);
WIRE 17 -1 (-2750 3800)(-2750 4000);
WIRE 17 -1 (-2750 4000)(-2750 4075);
FORCEPROP 2 LAST SIG_NAME DMI_CPU0_PCH_RX_C_DP<3:0>
J 0
(-2685 4110);
DISPLAY 0.617021 (-2685 4110);
PAINT ORANGE (-2685 4110);
WIRE 17 -1 (-4200 4350)(-4200 4550);
WIRE 17 -1 (-4200 4550)(-4200 4750);
WIRE 17 -1 (-4200 4750)(-4200 4950);
WIRE 17 -1 (-4200 4950)(-4200 5025);
WIRE 17 -1 (-4200 5025)(-5000 5025);
FORCEPROP 2 LAST SIG_NAME DMI_CPU0_PCH_TX_DP<3:0>
J 0
(-4985 5035);
DISPLAY 0.617021 (-4985 5035);
PAINT ORANGE (-4985 5035);
WIRE 17 -1 (-4200 3800)(-4200 4000);
WIRE 17 -1 (-4200 3600)(-4200 3800);
WIRE 17 -1 (-4200 4000)(-4200 4075);
WIRE 17 -1 (-4200 4075)(-5000 4075);
FORCEPROP 2 LAST SIG_NAME DMI_CPU0_PCH_RX_DP<3:0>
J 0
(-4985 4085);
DISPLAY 0.617021 (-4985 4085);
PAINT ORANGE (-4985 4085);
WIRE 17 -1 (-4200 3400)(-4200 3600);
WIRE 17 -1 (1250 5025)(2100 5025);
WIRE 17 -1 (1250 4075)(2100 4075);
WIRE 17 -1 (-2750 5025)(-1950 5025);
WIRE 17 -1 (-2750 4075)(-1950 4075);
WIRE 16 -1 (-4100 4925)(-3750 4925);
WIRE 16 -1 (-4100 4725)(-3400 4725);
WIRE 16 -1 (-4100 4525)(-3750 4525);
WIRE 16 -1 (-4100 3375)(-3400 3375);
WIRE 16 -1 (-4100 3575)(-3750 3575);
WIRE 16 -1 (-4100 3775)(-3400 3775);
WIRE 16 -1 (-4100 3975)(-3750 3975);
WIRE 16 -1 (-4100 4325)(-3400 4325);
WIRE 16 -1 (-3200 3375)(-2850 3375);
WIRE 16 -1 (-2850 3775)(-3200 3775);
WIRE 16 -1 (-3550 3975)(-2850 3975);
WIRE 16 -1 (-3550 3575)(-2850 3575);
WIRE 16 -1 (-3550 4925)(-2850 4925);
WIRE 16 -1 (-2850 4725)(-3200 4725);
WIRE 16 -1 (-3550 4525)(-2850 4525);
WIRE 16 -1 (-3200 4325)(-2850 4325);
WIRE 16 -1 (-100 3375)(650 3375);
WIRE 16 273 (-5250 3175)(2525 3175);
WIRE 16 -1 (-75 4325)(650 4325);
WIRE 16 -1 (-75 4525)(300 4525);
WIRE 16 -1 (-75 4725)(650 4725);
WIRE 16 -1 (-75 4925)(300 4925);
WIRE 16 -1 (-100 3575)(300 3575);
WIRE 16 -1 (-100 3775)(650 3775);
WIRE 16 -1 (-100 3975)(300 3975);
WIRE 16 -1 (850 3375)(1150 3375);
WIRE 16 -1 (500 3575)(1150 3575);
WIRE 16 -1 (1150 3775)(850 3775);
WIRE 16 -1 (500 3975)(1150 3975);
WIRE 16 -1 (850 4325)(1150 4325);
WIRE 16 -1 (500 4525)(1150 4525);
WIRE 16 -1 (1150 4725)(850 4725);
WIRE 16 -1 (500 4925)(1150 4925);
FORCENOTE
BOM_COST=SB
(-5275 3225) 0;
DISPLAY LEFT (-5275 3225);
DISPLAY 1.021277 (-5275 3225);
PAINT PURPLE (-5275 3225);
FORCENOTE
ROOM=DMI
(-5275 3300) 0;
DISPLAY LEFT (-5275 3300);
DISPLAY 1.021277 (-5275 3300);
PAINT PURPLE (-5275 3300);
FORCENOTE
CAD NOTE:
(-1725 3600) 0;
DISPLAY LEFT (-1725 3600);
DISPLAY 1.021277 (-1725 3600);
PAINT PURPLE (-1725 3600);
FORCENOTE
PLACE CAPS NEAR PCH
(-1725 3525) 0;
DISPLAY LEFT (-1725 3525);
DISPLAY 1.021277 (-1725 3525);
PAINT PURPLE (-1725 3525);
FORCENOTE
DMI AC CAPS
(-1800 5225) 0;
DISPLAY LEFT (-1800 5225);
DISPLAY 1.595745 (-1800 5225);
PAINT PURPLE (-1800 5225);
QUIT
